FILE_TYPE = MACRO_DRAWING;
SET COLOR_WIRE YELLOW;
SET COLOR_PROP ORANGE;
SET COLOR_DOT WHITE;
SET COLOR_ARC YELLOW;
SET COLOR_BODY GREEN;
SET COLOR_NOTE PURPLE;
SET PROP_DISPLAY VALUE;
SET PAGE_NUMBER P171;
FORCEADD OFFPAGE..1
(-7750 1750);
FORCEPROP 2 LAST $XR5 199 
J 0
(-8602 1750);
DISPLAY 0.638298 (-8602 1750);
PAINT MONO (-8602 1750);
FORCEPROP 2 LAST $XR4 198 
J 0
(-8482 1750);
DISPLAY 0.638298 (-8482 1750);
PAINT MONO (-8482 1750);
FORCEPROP 2 LAST $XR3 196 
J 0
(-8362 1750);
DISPLAY 0.638298 (-8362 1750);
PAINT MONO (-8362 1750);
FORCEPROP 2 LAST $XR2 195 
J 0
(-8242 1750);
DISPLAY 0.638298 (-8242 1750);
PAINT MONO (-8242 1750);
FORCEPROP 2 LAST $XR1 194 
J 0
(-8122 1750);
DISPLAY 0.638298 (-8122 1750);
PAINT MONO (-8122 1750);
FORCEPROP 2 LAST $XR0 193 
J 0
(-8002 1750);
DISPLAY 0.638298 (-8002 1750);
PAINT MONO (-8002 1750);
FORCEPROP 2 LAST CDS_LIB standard
J 0
(-7750 1750);
DISPLAY INVISIBLE (-7750 1750);
FORCEPROP 1 LAST OFFPAGE TRUE
J 0
(-7425 1625);
DISPLAY 0.872340 (-7425 1625);
PAINT GREEN (-7425 1625);
DISPLAY INVISIBLE (-7425 1625);
FORCEPROP 1 LAST COMMENT_BODY TRUE
J 0
(-7625 1650);
DISPLAY 0.872340 (-7625 1650);
PAINT GREEN (-7625 1650);
DISPLAY INVISIBLE (-7625 1650);
FORCEPROP 2 LAST PATH I1
J 0
(-8025 1800);
DISPLAY 0.680851 (-8025 1800);
DISPLAY INVISIBLE (-8025 1800);
FORCEADD UNIVERSAL_GND..1
(-7200 2000);
FORCEPROP 3 LASTPIN (-7200 2050) SIG_NAME GND\g
J 0
(-7190 2060);
DISPLAY 0.659574 (-7190 2060);
PAINT MONO (-7190 2060);
DISPLAY INVISIBLE (-7190 2060);
FORCEPROP 2 LAST CDS_LIB pure_quanta_power
J 0
(-7200 2000);
DISPLAY INVISIBLE (-7200 2000);
FORCEPROP 1 LAST HDL_POWER GND
J 1
(-7175 1925);
DISPLAY 0.872340 (-7175 1925);
PAINT GREEN (-7175 1925);
DISPLAY INVISIBLE (-7175 1925);
FORCEPROP 1 LAST PATH I10
J 0
(-7125 2000);
DISPLAY 0.872340 (-7125 2000);
PAINT AQUA (-7125 2000);
DISPLAY INVISIBLE (-7125 2000);
FORCEADD Q_CAP..1
(-7200 2200);
FORCEPROP 1 LAST LOCATION PC151
J 0
(-7150 2300);
DISPLAY 0.489362 (-7150 2300);
PAINT SKYBLUE (-7150 2300);
FORCEPROP 0 LAST $SEC 1
J 0
(-7150 2350);
DISPLAY 0.680851 (-7150 2350);
PAINT MONO (-7150 2350);
DISPLAY INVISIBLE (-7150 2350);
FORCEPROP 0 LAST CDS_SEC 1
J 0
(-7150 2350);
DISPLAY 1.021277 (-7150 2350);
DISPLAY INVISIBLE (-7150 2350);
FORCEPROP 1 LASTPIN (-7200 2300) $PN 1
J 0
(-7190 2280);
DISPLAY 0.489362 (-7190 2280);
PAINT MONO (-7190 2280);
FORCEPROP 1 LASTPIN (-7200 2100) $PN 2
J 0
(-7190 2080);
DISPLAY 0.489362 (-7190 2080);
PAINT MONO (-7190 2080);
FORCEPROP 1 LAST PACK_TYPE C0402
J 0
(-7150 2000);
DISPLAY 0.489362 (-7150 2000);
PAINT SKYBLUE (-7150 2000);
FORCEPROP 1 LAST VOLTAGE 10V
J 0
(-7150 2200);
DISPLAY 0.489362 (-7150 2200);
PAINT SKYBLUE (-7150 2200);
FORCEPROP 1 LAST VALUE 2.2UF
J 0
(-7150 2250);
DISPLAY 0.489362 (-7150 2250);
PAINT SKYBLUE (-7150 2250);
FORCEPROP 1 LAST TOLERANCE 10%
J 0
(-7150 2150);
DISPLAY 0.489362 (-7150 2150);
PAINT SKYBLUE (-7150 2150);
FORCEPROP 1 LAST MATERIAL X6S
J 0
(-7150 2100);
DISPLAY 0.489362 (-7150 2100);
PAINT SKYBLUE (-7150 2100);
FORCEPROP 2 LAST CDS_LIB pure_quanta
J 0
(-7200 2200);
DISPLAY INVISIBLE (-7200 2200);
FORCEPROP 1 LAST PATH I11
J 0
(-7150 2350);
DISPLAY 0.978723 (-7150 2350);
PAINT WHITE (-7150 2350);
DISPLAY INVISIBLE (-7150 2350);
FORCEPROP 1 LAST PART_NUMBER CH5222KEB01
J 0
(-7150 2050);
DISPLAY 0.489362 (-7150 2050);
PAINT SKYBLUE (-7150 2050);
DISPLAY INVISIBLE (-7150 2050);
FORCEADD UNIVERSAL_GND..1
(-6850 2450);
FORCEPROP 3 LASTPIN (-6850 2500) SIG_NAME GND\g
J 0
(-6840 2510);
DISPLAY 0.659574 (-6840 2510);
PAINT MONO (-6840 2510);
DISPLAY INVISIBLE (-6840 2510);
FORCEPROP 2 LAST CDS_LIB pure_quanta_power
J 0
(-6850 2450);
DISPLAY INVISIBLE (-6850 2450);
FORCEPROP 1 LAST HDL_POWER GND
J 1
(-6825 2375);
DISPLAY 0.872340 (-6825 2375);
PAINT GREEN (-6825 2375);
DISPLAY INVISIBLE (-6825 2375);
FORCEPROP 1 LAST PATH I12
J 0
(-6775 2450);
DISPLAY 0.872340 (-6775 2450);
PAINT AQUA (-6775 2450);
DISPLAY INVISIBLE (-6775 2450);
FORCEADD Q_RES..2
(-7200 2700);
FORCEPROP 1 LAST LOCATION PR430
J 0
(-7155 2825);
DISPLAY 0.489362 (-7155 2825);
PAINT SKYBLUE (-7155 2825);
FORCEPROP 0 LAST $SEC 1
J 0
(-7150 2875);
DISPLAY 0.680851 (-7150 2875);
PAINT MONO (-7150 2875);
DISPLAY INVISIBLE (-7150 2875);
FORCEPROP 0 LAST CDS_SEC 1
J 0
(-7150 2875);
DISPLAY 1.021277 (-7150 2875);
DISPLAY INVISIBLE (-7150 2875);
FORCEPROP 1 LASTPIN (-7200 2800) $PN 1
J 0
(-7195 2762);
DISPLAY 0.489362 (-7195 2762);
PAINT MONO (-7195 2762);
FORCEPROP 1 LASTPIN (-7200 2600) $PN 2
J 0
(-7195 2610);
DISPLAY 0.489362 (-7195 2610);
PAINT MONO (-7195 2610);
FORCEPROP 1 LAST WATTAGE 1/16W
J 0
(-7150 2675);
DISPLAY 0.489362 (-7150 2675);
PAINT SKYBLUE (-7150 2675);
FORCEPROP 1 LAST MATERIAL CHIP
J 0
(-7150 2625);
DISPLAY 0.489362 (-7150 2625);
PAINT SKYBLUE (-7150 2625);
FORCEPROP 1 LAST TOLERANCE 1%
J 0
(-7150 2725);
DISPLAY 0.489362 (-7150 2725);
PAINT SKYBLUE (-7150 2725);
FORCEPROP 1 LAST VALUE 2.2
J 0
(-7150 2775);
DISPLAY 0.489362 (-7150 2775);
PAINT SKYBLUE (-7150 2775);
FORCEPROP 1 LAST PACK_TYPE 0402LF
J 0
(-7150 2525);
DISPLAY 0.489362 (-7150 2525);
PAINT SKYBLUE (-7150 2525);
FORCEPROP 2 LAST CDS_LIB pure_quanta
J 0
(-7200 2700);
DISPLAY INVISIBLE (-7200 2700);
FORCEPROP 1 LAST PATH I13
J 0
(-7150 2875);
DISPLAY 0.978723 (-7150 2875);
PAINT WHITE (-7150 2875);
DISPLAY INVISIBLE (-7150 2875);
FORCEPROP 1 LAST PART_NUMBER CS-2202FB01
J 0
(-7150 2575);
DISPLAY 0.489362 (-7150 2575);
PAINT SKYBLUE (-7150 2575);
DISPLAY INVISIBLE (-7150 2575);
FORCEADD Q_CAP..1
(-6850 2725);
FORCEPROP 1 LAST LOCATION PC152_C0P0_6
J 0
(-6800 2825);
DISPLAY 0.489362 (-6800 2825);
PAINT SKYBLUE (-6800 2825);
FORCEPROP 0 LAST $SEC 1
J 0
(-6800 2875);
DISPLAY 0.680851 (-6800 2875);
PAINT MONO (-6800 2875);
DISPLAY INVISIBLE (-6800 2875);
FORCEPROP 0 LAST CDS_SEC 1
J 0
(-6800 2875);
DISPLAY 1.021277 (-6800 2875);
DISPLAY INVISIBLE (-6800 2875);
FORCEPROP 1 LASTPIN (-6850 2825) $PN 1
J 0
(-6840 2805);
DISPLAY 0.489362 (-6840 2805);
PAINT MONO (-6840 2805);
FORCEPROP 1 LASTPIN (-6850 2625) $PN 2
J 0
(-6840 2605);
DISPLAY 0.489362 (-6840 2605);
PAINT MONO (-6840 2605);
FORCEPROP 1 LAST PACK_TYPE C0402
J 0
(-6800 2525);
DISPLAY 0.489362 (-6800 2525);
PAINT SKYBLUE (-6800 2525);
FORCEPROP 1 LAST MATERIAL X6S
J 0
(-6800 2625);
DISPLAY 0.489362 (-6800 2625);
PAINT SKYBLUE (-6800 2625);
FORCEPROP 1 LAST TOLERANCE 10%
J 0
(-6800 2675);
DISPLAY 0.489362 (-6800 2675);
PAINT SKYBLUE (-6800 2675);
FORCEPROP 1 LAST VOLTAGE 10V
J 0
(-6800 2725);
DISPLAY 0.489362 (-6800 2725);
PAINT SKYBLUE (-6800 2725);
FORCEPROP 1 LAST VALUE 2.2UF
J 0
(-6800 2775);
DISPLAY 0.489362 (-6800 2775);
PAINT SKYBLUE (-6800 2775);
FORCEPROP 2 LAST CDS_LIB pure_quanta
J 0
(-6850 2725);
DISPLAY INVISIBLE (-6850 2725);
FORCEPROP 1 LAST PATH I14
J 0
(-6800 2875);
DISPLAY 0.978723 (-6800 2875);
PAINT WHITE (-6800 2875);
DISPLAY INVISIBLE (-6800 2875);
FORCEPROP 1 LAST PART_NUMBER CH5222KEB01
J 0
(-6800 2575);
DISPLAY 0.489362 (-6800 2575);
PAINT SKYBLUE (-6800 2575);
DISPLAY INVISIBLE (-6800 2575);
FORCEADD UNIVERSAL_GND..1
(-7525 4025);
FORCEPROP 3 LASTPIN (-7525 4075) SIG_NAME GND\g
J 0
(-7515 4085);
DISPLAY 0.659574 (-7515 4085);
PAINT MONO (-7515 4085);
DISPLAY INVISIBLE (-7515 4085);
FORCEPROP 2 LAST CDS_LIB pure_quanta_power
J 0
(-7525 4025);
DISPLAY INVISIBLE (-7525 4025);
FORCEPROP 1 LAST HDL_POWER GND
J 1
(-7500 3950);
DISPLAY 0.872340 (-7500 3950);
PAINT GREEN (-7500 3950);
DISPLAY INVISIBLE (-7500 3950);
FORCEPROP 1 LAST PATH I15
J 0
(-7450 4025);
DISPLAY 0.872340 (-7450 4025);
PAINT AQUA (-7450 4025);
DISPLAY INVISIBLE (-7450 4025);
FORCEADD VCC_CORE..1
(-7200 3125);
FORCEPROP 3 LASTPIN (-7200 3075) SIG_NAME PVDDCR_CPU0_P0_PVCC\g
J 0
(-7190 3085);
DISPLAY 0.659574 (-7190 3085);
PAINT MONO (-7190 3085);
DISPLAY INVISIBLE (-7190 3085);
FORCEPROP 1 LAST HDL_POWER PVDDCR_CPU0_P0_PVCC
J 1
(-7200 3175);
DISPLAY 0.489362 (-7200 3175);
PAINT GREEN (-7200 3175);
FORCEPROP 2 LAST CDS_LIB pure_quanta_power
J 0
(-7200 3125);
DISPLAY INVISIBLE (-7200 3125);
FORCEPROP 1 LAST PATH I16
J 0
(-7150 3150);
DISPLAY 0.872340 (-7150 3150);
PAINT AQUA (-7150 3150);
DISPLAY INVISIBLE (-7150 3150);
FORCEADD OFFPAGE..1
(-6800 3975);
FORCEPROP 2 LAST $XR0 193 
J 0
(-7082 3975);
DISPLAY 0.638298 (-7082 3975);
PAINT MONO (-7082 3975);
FORCEPROP 2 LAST CDS_LIB standard
J 2
(-6800 3975);
DISPLAY INVISIBLE (-6800 3975);
FORCEPROP 1 LAST OFFPAGE TRUE
J 0
(-6475 3850);
DISPLAY 0.872340 (-6475 3850);
PAINT GREEN (-6475 3850);
DISPLAY INVISIBLE (-6475 3850);
FORCEPROP 1 LAST COMMENT_BODY TRUE
J 0
(-6675 3875);
DISPLAY 0.872340 (-6675 3875);
PAINT GREEN (-6675 3875);
DISPLAY INVISIBLE (-6675 3875);
FORCEPROP 2 LAST PATH I17
J 0
(-7050 4025);
DISPLAY 0.680851 (-7050 4025);
DISPLAY INVISIBLE (-7050 4025);
FORCEADD ISL99390FRZTR5935..1
(-5700 4575);
FORCEPROP 1 LAST LOCATION PU48
J 0
(-6000 5450);
DISPLAY 0.489362 (-6000 5450);
PAINT SKYBLUE (-6000 5450);
FORCEPROP 0 LAST $SEC 1
J 0
(-6000 5600);
DISPLAY 0.680851 (-6000 5600);
PAINT MONO (-6000 5600);
DISPLAY INVISIBLE (-6000 5600);
FORCEPROP 0 LAST CDS_SEC 1
J 0
(-6000 5600);
DISPLAY 1.021277 (-6000 5600);
DISPLAY INVISIBLE (-6000 5600);
FORCEPROP 0 LASTPIN (-5300 4125) $PN 2
J 0
(-5290 4135);
DISPLAY 0.489362 (-5290 4135);
PAINT MONO (-5290 4135);
FORCEPROP 0 LASTPIN (-5300 4925) $PN 33
J 0
(-5290 4935);
DISPLAY 0.489362 (-5290 4935);
PAINT MONO (-5290 4935);
FORCEPROP 0 LASTPIN (-6150 4325) $PN 31
J 2
(-6160 4335);
DISPLAY 0.489362 (-6160 4335);
PAINT MONO (-6160 4335);
FORCEPROP 0 LASTPIN (-6150 4725) $PN 35
J 2
(-6160 4735);
DISPLAY 0.489362 (-6160 4735);
PAINT MONO (-6160 4735);
FORCEPROP 0 LASTPIN (-5300 4275) $PN 6
J 0
(-5290 4285);
DISPLAY 0.489362 (-5290 4285);
PAINT MONO (-5290 4285);
FORCEPROP 0 LASTPIN (-5300 4225) $PN 41
J 0
(-5290 4235);
DISPLAY 0.489362 (-5290 4235);
PAINT MONO (-5290 4235);
FORCEPROP 0 LASTPIN (-6150 4575) $PN 38
J 2
(-6160 4585);
DISPLAY 0.489362 (-6160 4585);
PAINT MONO (-6160 4585);
FORCEPROP 0 LASTPIN (-6150 4275) $PN 37
J 2
(-6160 4285);
DISPLAY 0.489362 (-6160 4285);
PAINT MONO (-6160 4285);
FORCEPROP 0 LASTPIN (-5300 4075) $PN 5
J 0
(-5290 4085);
DISPLAY 0.489362 (-5290 4085);
PAINT MONO (-5290 4085);
FORCEPROP 0 LASTPIN (-5300 4025) $PN 7_9-20_24
J 0
(-5290 4035);
DISPLAY 0.489362 (-5290 4035);
PAINT MONO (-5290 4035);
FORCEPROP 0 LASTPIN (-5300 3975) $PN 40
J 0
(-5290 3985);
DISPLAY 0.489362 (-5290 3985);
PAINT MONO (-5290 3985);
FORCEPROP 0 LASTPIN (-5300 4675) $PN 32
J 0
(-5290 4685);
DISPLAY 0.489362 (-5290 4685);
PAINT MONO (-5290 4685);
FORCEPROP 0 LASTPIN (-6150 5225) $PN 4
J 2
(-6160 5235);
DISPLAY 0.489362 (-6160 5235);
PAINT MONO (-6160 5235);
FORCEPROP 0 LASTPIN (-6150 3975) $PN 34
J 2
(-6160 3985);
DISPLAY 0.489362 (-6160 3985);
PAINT MONO (-6160 3985);
FORCEPROP 0 LASTPIN (-6150 4475) $PN 39
J 2
(-6160 4485);
DISPLAY 0.489362 (-6160 4485);
PAINT MONO (-6160 4485);
FORCEPROP 0 LASTPIN (-5300 4575) $PN 10_19
J 0
(-5290 4585);
DISPLAY 0.489362 (-5290 4585);
PAINT MONO (-5290 4585);
FORCEPROP 0 LASTPIN (-6150 4075) $PN 36
J 2
(-6160 4085);
DISPLAY 0.489362 (-6160 4085);
PAINT MONO (-6160 4085);
FORCEPROP 0 LASTPIN (-6150 4925) $PN 3
J 2
(-6160 4935);
DISPLAY 0.489362 (-6160 4935);
PAINT MONO (-6160 4935);
FORCEPROP 0 LASTPIN (-5300 5225) $PN 25_29
J 0
(-5290 5235);
DISPLAY 0.489362 (-5290 5235);
PAINT MONO (-5290 5235);
FORCEPROP 0 LASTPIN (-5300 5175) $PN 30
J 0
(-5290 5185);
DISPLAY 0.489362 (-5290 5185);
PAINT MONO (-5290 5185);
FORCEPROP 0 LASTPIN (-5300 4325) $PN 1
J 0
(-5290 4335);
DISPLAY 0.489362 (-5290 4335);
PAINT MONO (-5290 4335);
FORCEPROP 1 LAST MATERIAL IC
J 0
(-6000 5300);
DISPLAY 0.489362 (-6000 5300);
PAINT SKYBLUE (-6000 5300);
FORCEPROP 2 LAST PART_TYPE SMLF
J 0
(-6000 5550);
DISPLAY 1.021277 (-6000 5550);
FORCEPROP 2 LAST VALUE ISL99390FRZ-TR5935
J 0
(-6000 5500);
DISPLAY 0.489362 (-6000 5500);
PAINT SKYBLUE (-6000 5500);
FORCEPROP 1 LAST CDS_LMAN_SYM_OUTLINE -300,700,250,-650
J 0
(-5700 4575);
DISPLAY 0.468085 (-5700 4575);
PAINT GREEN (-5700 4575);
DISPLAY INVISIBLE (-5700 4575);
FORCEPROP 1 LAST NEEDS_NO_SIZE TRUE
J 0
(-5700 4575);
DISPLAY 0.723404 (-5700 4575);
PAINT GREEN (-5700 4575);
DISPLAY INVISIBLE (-5700 4575);
FORCEPROP 2 LAST CDS_LIB pure_quanta
J 0
(-5700 4575);
DISPLAY INVISIBLE (-5700 4575);
FORCEPROP 1 LAST PATH I18
J 0
(-5700 4575);
DISPLAY 0.723404 (-5700 4575);
PAINT GREEN (-5700 4575);
DISPLAY INVISIBLE (-5700 4575);
FORCEPROP 1 LAST PART_NUMBER AL099390004
J 0
(-6000 5375);
DISPLAY 0.489362 (-6000 5375);
PAINT SKYBLUE (-6000 5375);
DISPLAY INVISIBLE (-6000 5375);
FORCEADD UNIVERSAL_GND..1
(-5150 1125);
FORCEPROP 3 LASTPIN (-5150 1175) SIG_NAME GND\g
J 0
(-5140 1185);
DISPLAY 0.659574 (-5140 1185);
PAINT MONO (-5140 1185);
DISPLAY INVISIBLE (-5140 1185);
FORCEPROP 2 LAST CDS_LIB pure_quanta_power
J 0
(-5150 1125);
DISPLAY INVISIBLE (-5150 1125);
FORCEPROP 1 LAST HDL_POWER GND
J 1
(-5125 1050);
DISPLAY 0.872340 (-5125 1050);
PAINT GREEN (-5125 1050);
DISPLAY INVISIBLE (-5125 1050);
FORCEPROP 1 LAST PATH I19
J 0
(-5075 1125);
DISPLAY 0.872340 (-5075 1125);
PAINT AQUA (-5075 1125);
DISPLAY INVISIBLE (-5075 1125);
FORCEADD OFFPAGE..1
(-7750 4475);
FORCEPROP 2 LAST $XR5 199 
J 0
(-8602 4475);
DISPLAY 0.638298 (-8602 4475);
PAINT MONO (-8602 4475);
FORCEPROP 2 LAST $XR4 198 
J 0
(-8482 4475);
DISPLAY 0.638298 (-8482 4475);
PAINT MONO (-8482 4475);
FORCEPROP 2 LAST $XR3 196 
J 0
(-8362 4475);
DISPLAY 0.638298 (-8362 4475);
PAINT MONO (-8362 4475);
FORCEPROP 2 LAST $XR2 195 
J 0
(-8242 4475);
DISPLAY 0.638298 (-8242 4475);
PAINT MONO (-8242 4475);
FORCEPROP 2 LAST $XR1 194 
J 0
(-8122 4475);
DISPLAY 0.638298 (-8122 4475);
PAINT MONO (-8122 4475);
FORCEPROP 2 LAST $XR0 193 
J 0
(-8002 4475);
DISPLAY 0.638298 (-8002 4475);
PAINT MONO (-8002 4475);
FORCEPROP 2 LAST CDS_LIB standard
J 0
(-7750 4475);
DISPLAY INVISIBLE (-7750 4475);
FORCEPROP 1 LAST OFFPAGE TRUE
J 0
(-7425 4350);
DISPLAY 0.872340 (-7425 4350);
PAINT GREEN (-7425 4350);
DISPLAY INVISIBLE (-7425 4350);
FORCEPROP 1 LAST COMMENT_BODY TRUE
J 0
(-7625 4375);
DISPLAY 0.872340 (-7625 4375);
PAINT GREEN (-7625 4375);
DISPLAY INVISIBLE (-7625 4375);
FORCEPROP 2 LAST PATH I2
J 0
(-8025 4525);
DISPLAY 0.680851 (-8025 4525);
DISPLAY INVISIBLE (-8025 4525);
FORCEADD UNIVERSAL_GND..1
(-4225 950);
FORCEPROP 3 LASTPIN (-4225 1000) SIG_NAME GND\g
J 0
(-4215 1010);
DISPLAY 0.659574 (-4215 1010);
PAINT MONO (-4215 1010);
DISPLAY INVISIBLE (-4215 1010);
FORCEPROP 2 LAST CDS_LIB pure_quanta_power
J 0
(-4225 950);
DISPLAY INVISIBLE (-4225 950);
FORCEPROP 1 LAST HDL_POWER GND
J 1
(-4200 875);
DISPLAY 0.872340 (-4200 875);
PAINT GREEN (-4200 875);
DISPLAY INVISIBLE (-4200 875);
FORCEPROP 1 LAST PATH I20
J 0
(-4150 950);
DISPLAY 0.872340 (-4150 950);
PAINT AQUA (-4150 950);
DISPLAY INVISIBLE (-4150 950);
FORCEADD Q_RES..1
(-3900 800);
FORCEPROP 1 LAST LOCATION PR433
J 0
(-3925 850);
DISPLAY 0.489362 (-3925 850);
PAINT SKYBLUE (-3925 850);
FORCEPROP 0 LAST $SEC 1
J 0
(-3900 875);
DISPLAY 0.680851 (-3900 875);
PAINT MONO (-3900 875);
DISPLAY INVISIBLE (-3900 875);
FORCEPROP 0 LAST CDS_SEC 1
J 0
(-3900 875);
DISPLAY 1.021277 (-3900 875);
DISPLAY INVISIBLE (-3900 875);
FORCEPROP 1 LASTPIN (-4000 800) $PN 1
J 0
(-3988 812);
DISPLAY 0.489362 (-3988 812);
PAINT MONO (-3988 812);
FORCEPROP 1 LASTPIN (-3800 800) $PN 2
J 0
(-3838 812);
DISPLAY 0.489362 (-3838 812);
PAINT MONO (-3838 812);
FORCEPROP 1 LAST WATTAGE 1/16W
J 0
(-3800 750);
DISPLAY 0.489362 (-3800 750);
PAINT SKYBLUE (-3800 750);
FORCEPROP 1 LAST MATERIAL CHIP
J 0
(-4150 700);
DISPLAY 0.489362 (-4150 700);
PAINT SKYBLUE (-4150 700);
FORCEPROP 1 LAST TOLERANCE 5%
J 0
(-3775 825);
DISPLAY 0.489362 (-3775 825);
PAINT SKYBLUE (-3775 825);
FORCEPROP 1 LAST VALUE 0
J 2
(-4025 825);
DISPLAY 0.489362 (-4025 825);
PAINT SKYBLUE (-4025 825);
FORCEPROP 1 LAST PACK_TYPE 0402LF
J 0
(-3800 700);
DISPLAY 0.489362 (-3800 700);
PAINT SKYBLUE (-3800 700);
FORCEPROP 2 LAST CDS_LIB pure_quanta
J 0
(-3900 800);
DISPLAY INVISIBLE (-3900 800);
FORCEPROP 1 LAST PATH I21
J 0
(-3950 950);
DISPLAY 0.978723 (-3950 950);
PAINT WHITE (-3950 950);
DISPLAY INVISIBLE (-3950 950);
FORCEPROP 1 LAST PART_NUMBER CS00002JB13
J 0
(-4150 750);
DISPLAY 0.489362 (-4150 750);
PAINT SKYBLUE (-4150 750);
DISPLAY INVISIBLE (-4150 750);
FORCEADD Q_RES..2
(-4225 1175);
FORCEPROP 1 LAST LOCATION PR500
J 0
(-4180 1300);
DISPLAY 0.489362 (-4180 1300);
PAINT SKYBLUE (-4180 1300);
FORCEPROP 0 LAST $SEC 1
J 0
(-4175 1350);
DISPLAY 0.680851 (-4175 1350);
PAINT MONO (-4175 1350);
DISPLAY INVISIBLE (-4175 1350);
FORCEPROP 0 LAST CDS_SEC 1
J 0
(-4175 1350);
DISPLAY 1.021277 (-4175 1350);
DISPLAY INVISIBLE (-4175 1350);
FORCEPROP 1 LASTPIN (-4225 1275) $PN 1
J 0
(-4220 1237);
DISPLAY 0.489362 (-4220 1237);
PAINT MONO (-4220 1237);
FORCEPROP 1 LASTPIN (-4225 1075) $PN 2
J 0
(-4220 1085);
DISPLAY 0.489362 (-4220 1085);
PAINT MONO (-4220 1085);
FORCEPROP 1 LAST MATERIAL EMPTY
J 0
(-4185 1100);
DISPLAY 0.489362 (-4185 1100);
PAINT RED (-4185 1100);
FORCEPROP 1 LAST WATTAGE 1/8W
J 0
(-4185 1150);
DISPLAY 0.489362 (-4185 1150);
PAINT SKYBLUE (-4185 1150);
FORCEPROP 1 LAST PACK_TYPE 0402LF
J 0
(-4185 1000);
DISPLAY 0.489362 (-4185 1000);
PAINT SKYBLUE (-4185 1000);
FORCEPROP 1 LAST VALUE 1.5
J 0
(-4180 1250);
DISPLAY 0.489362 (-4180 1250);
PAINT SKYBLUE (-4180 1250);
FORCEPROP 1 LAST TOLERANCE 1%
J 0
(-4180 1200);
DISPLAY 0.489362 (-4180 1200);
PAINT SKYBLUE (-4180 1200);
FORCEPROP 2 LAST CDS_LIB pure_quanta
J 0
(-4225 1175);
DISPLAY INVISIBLE (-4225 1175);
FORCEPROP 1 LAST PATH I22
J 0
(-4175 1350);
DISPLAY 0.978723 (-4175 1350);
PAINT WHITE (-4175 1350);
DISPLAY INVISIBLE (-4175 1350);
FORCEPROP 1 LAST PART_NUMBER CS-1504FB00
J 0
(-4185 1050);
DISPLAY 0.489362 (-4185 1050);
PAINT SKYBLUE (-4185 1050);
DISPLAY INVISIBLE (-4185 1050);
FORCEADD Q_CAP..1
(-4225 1675);
FORCEPROP 1 LAST LOCATION PC182
J 0
(-4175 1775);
DISPLAY 0.489362 (-4175 1775);
PAINT SKYBLUE (-4175 1775);
FORCEPROP 0 LAST $SEC 1
J 0
(-4175 1825);
DISPLAY 0.680851 (-4175 1825);
PAINT MONO (-4175 1825);
DISPLAY INVISIBLE (-4175 1825);
FORCEPROP 0 LAST CDS_SEC 1
J 0
(-4175 1825);
DISPLAY 1.021277 (-4175 1825);
DISPLAY INVISIBLE (-4175 1825);
FORCEPROP 1 LASTPIN (-4225 1775) $PN 1
J 0
(-4215 1755);
DISPLAY 0.489362 (-4215 1755);
PAINT MONO (-4215 1755);
FORCEPROP 1 LASTPIN (-4225 1575) $PN 2
J 0
(-4215 1555);
DISPLAY 0.489362 (-4215 1555);
PAINT MONO (-4215 1555);
FORCEPROP 1 LAST PACK_TYPE C0402
J 0
(-4175 1475);
DISPLAY 0.489362 (-4175 1475);
PAINT SKYBLUE (-4175 1475);
FORCEPROP 1 LAST TOLERANCE 10%
J 0
(-4175 1625);
DISPLAY 0.489362 (-4175 1625);
PAINT SKYBLUE (-4175 1625);
FORCEPROP 1 LAST VOLTAGE 50V
J 0
(-4175 1675);
DISPLAY 0.489362 (-4175 1675);
PAINT SKYBLUE (-4175 1675);
FORCEPROP 1 LAST VALUE 560PF
J 0
(-4175 1725);
DISPLAY 0.489362 (-4175 1725);
PAINT SKYBLUE (-4175 1725);
FORCEPROP 1 LAST MATERIAL EMPTY
J 0
(-4175 1575);
DISPLAY 0.489362 (-4175 1575);
PAINT RED (-4175 1575);
FORCEPROP 2 LAST CDS_LIB pure_quanta
J 0
(-4225 1675);
DISPLAY INVISIBLE (-4225 1675);
FORCEPROP 1 LAST PATH I23
J 0
(-4175 1825);
DISPLAY 0.978723 (-4175 1825);
PAINT WHITE (-4175 1825);
DISPLAY INVISIBLE (-4175 1825);
FORCEPROP 1 LAST PART_NUMBER CH1566K1B09
J 0
(-4175 1525);
DISPLAY 0.489362 (-4175 1525);
PAINT SKYBLUE (-4175 1525);
DISPLAY INVISIBLE (-4175 1525);
FORCEADD Q_CAP..1
(-4950 2725);
FORCEPROP 1 LAST LOCATION PC153_6
J 0
(-4900 2825);
DISPLAY 0.489362 (-4900 2825);
PAINT SKYBLUE (-4900 2825);
FORCEPROP 0 LAST $SEC 1
J 0
(-4900 2875);
DISPLAY 0.680851 (-4900 2875);
PAINT MONO (-4900 2875);
DISPLAY INVISIBLE (-4900 2875);
FORCEPROP 0 LAST CDS_SEC 1
J 0
(-4900 2875);
DISPLAY 1.021277 (-4900 2875);
DISPLAY INVISIBLE (-4900 2875);
FORCEPROP 1 LASTPIN (-4950 2825) $PN 1
J 0
(-4940 2805);
DISPLAY 0.489362 (-4940 2805);
PAINT MONO (-4940 2805);
FORCEPROP 1 LASTPIN (-4950 2625) $PN 2
J 0
(-4940 2605);
DISPLAY 0.489362 (-4940 2605);
PAINT MONO (-4940 2605);
FORCEPROP 1 LAST PACK_TYPE 0402
J 0
(-4900 2525);
DISPLAY 0.489362 (-4900 2525);
PAINT SKYBLUE (-4900 2525);
FORCEPROP 1 LAST VOLTAGE 25V
J 0
(-4900 2725);
DISPLAY 0.489362 (-4900 2725);
PAINT SKYBLUE (-4900 2725);
FORCEPROP 1 LAST TOLERANCE 10%
J 0
(-4900 2675);
DISPLAY 0.489362 (-4900 2675);
PAINT SKYBLUE (-4900 2675);
FORCEPROP 1 LAST MATERIAL X7R
J 0
(-4900 2625);
DISPLAY 0.489362 (-4900 2625);
PAINT SKYBLUE (-4900 2625);
FORCEPROP 1 LAST VALUE 0.1UF
J 0
(-4900 2775);
DISPLAY 0.489362 (-4900 2775);
PAINT SKYBLUE (-4900 2775);
FORCEPROP 2 LAST CDS_LIB pure_quanta
J 0
(-4950 2725);
DISPLAY INVISIBLE (-4950 2725);
FORCEPROP 1 LAST PATH I24
J 0
(-4900 2875);
DISPLAY 0.978723 (-4900 2875);
PAINT WHITE (-4900 2875);
DISPLAY INVISIBLE (-4900 2875);
FORCEPROP 1 LAST PART_NUMBER CH4104K1B00
J 0
(-4900 2575);
DISPLAY 0.489362 (-4900 2575);
PAINT SKYBLUE (-4900 2575);
DISPLAY INVISIBLE (-4900 2575);
FORCEADD UNIVERSAL_GND..1
(-5150 3850);
FORCEPROP 3 LASTPIN (-5150 3900) SIG_NAME GND\g
J 0
(-5140 3910);
DISPLAY 0.659574 (-5140 3910);
PAINT MONO (-5140 3910);
DISPLAY INVISIBLE (-5140 3910);
FORCEPROP 2 LAST CDS_LIB pure_quanta_power
J 0
(-5150 3850);
DISPLAY INVISIBLE (-5150 3850);
FORCEPROP 1 LAST HDL_POWER GND
J 1
(-5125 3775);
DISPLAY 0.872340 (-5125 3775);
PAINT GREEN (-5125 3775);
DISPLAY INVISIBLE (-5125 3775);
FORCEPROP 1 LAST PATH I25
J 0
(-5075 3850);
DISPLAY 0.872340 (-5075 3850);
PAINT AQUA (-5075 3850);
DISPLAY INVISIBLE (-5075 3850);
FORCEADD Q_RES..1
(-4275 2200);
FORCEPROP 1 LAST LOCATION PR432
J 0
(-4300 2250);
DISPLAY 0.489362 (-4300 2250);
PAINT SKYBLUE (-4300 2250);
FORCEPROP 0 LAST $SEC 1
J 0
(-4250 2275);
DISPLAY 0.680851 (-4250 2275);
PAINT MONO (-4250 2275);
DISPLAY INVISIBLE (-4250 2275);
FORCEPROP 0 LAST CDS_SEC 1
J 0
(-4250 2275);
DISPLAY 1.021277 (-4250 2275);
DISPLAY INVISIBLE (-4250 2275);
FORCEPROP 1 LASTPIN (-4375 2200) $PN 1
J 0
(-4363 2212);
DISPLAY 0.489362 (-4363 2212);
PAINT MONO (-4363 2212);
FORCEPROP 1 LASTPIN (-4175 2200) $PN 2
J 0
(-4213 2212);
DISPLAY 0.489362 (-4213 2212);
PAINT MONO (-4213 2212);
FORCEPROP 1 LAST TOLERANCE 1%
J 0
(-4175 2225);
DISPLAY 0.489362 (-4175 2225);
PAINT SKYBLUE (-4175 2225);
FORCEPROP 1 LAST PACK_TYPE 0402LF
J 0
(-4175 2100);
DISPLAY 0.489362 (-4175 2100);
PAINT SKYBLUE (-4175 2100);
FORCEPROP 1 LAST WATTAGE 1/16W
J 0
(-4175 2150);
DISPLAY 0.489362 (-4175 2150);
PAINT SKYBLUE (-4175 2150);
FORCEPROP 1 LAST MATERIAL CHIP
J 0
(-4525 2100);
DISPLAY 0.489362 (-4525 2100);
PAINT SKYBLUE (-4525 2100);
FORCEPROP 1 LAST VALUE 5.6
J 2
(-4375 2225);
DISPLAY 0.489362 (-4375 2225);
PAINT SKYBLUE (-4375 2225);
FORCEPROP 2 LAST CDS_LIB pure_quanta
J 0
(-4275 2200);
DISPLAY INVISIBLE (-4275 2200);
FORCEPROP 1 LAST PATH I26
J 0
(-4325 2350);
DISPLAY 0.978723 (-4325 2350);
PAINT WHITE (-4325 2350);
DISPLAY INVISIBLE (-4325 2350);
FORCEPROP 1 LAST PART_NUMBER CS-5602FB01
J 0
(-4525 2150);
DISPLAY 0.489362 (-4525 2150);
PAINT SKYBLUE (-4525 2150);
DISPLAY INVISIBLE (-4525 2150);
FORCEADD Q_CAP..1
(-4575 2725);
FORCEPROP 1 LAST LOCATION PC154_6
J 0
(-4525 2825);
DISPLAY 0.489362 (-4525 2825);
PAINT SKYBLUE (-4525 2825);
FORCEPROP 0 LAST $SEC 1
J 0
(-4525 2850);
DISPLAY 0.680851 (-4525 2850);
PAINT MONO (-4525 2850);
DISPLAY INVISIBLE (-4525 2850);
FORCEPROP 0 LAST CDS_SEC 1
J 0
(-4525 2850);
DISPLAY 1.021277 (-4525 2850);
DISPLAY INVISIBLE (-4525 2850);
FORCEPROP 1 LASTPIN (-4575 2825) $PN 1
J 0
(-4565 2805);
DISPLAY 0.489362 (-4565 2805);
PAINT MONO (-4565 2805);
FORCEPROP 1 LASTPIN (-4575 2625) $PN 2
J 0
(-4565 2605);
DISPLAY 0.489362 (-4565 2605);
PAINT MONO (-4565 2605);
FORCEPROP 1 LAST VOLTAGE 25V
J 0
(-4525 2725);
DISPLAY 0.489362 (-4525 2725);
PAINT SKYBLUE (-4525 2725);
FORCEPROP 1 LAST TOLERANCE 10%
J 0
(-4525 2675);
DISPLAY 0.489362 (-4525 2675);
PAINT SKYBLUE (-4525 2675);
FORCEPROP 1 LAST MATERIAL X6S
J 0
(-4525 2625);
DISPLAY 0.489362 (-4525 2625);
PAINT SKYBLUE (-4525 2625);
FORCEPROP 1 LAST VALUE 1UF
J 0
(-4525 2775);
DISPLAY 0.489362 (-4525 2775);
PAINT SKYBLUE (-4525 2775);
FORCEPROP 1 LAST PACK_TYPE C0402
J 0
(-4525 2525);
DISPLAY 0.489362 (-4525 2525);
PAINT SKYBLUE (-4525 2525);
FORCEPROP 2 LAST CDS_LIB pure_quanta
J 0
(-4575 2725);
DISPLAY INVISIBLE (-4575 2725);
FORCEPROP 1 LAST PATH I27
J 0
(-4525 2875);
DISPLAY 0.978723 (-4525 2875);
PAINT WHITE (-4525 2875);
DISPLAY INVISIBLE (-4525 2875);
FORCEPROP 1 LAST PART_NUMBER CH5104KEB02
J 0
(-4525 2575);
DISPLAY 0.489362 (-4525 2575);
PAINT SKYBLUE (-4525 2575);
DISPLAY INVISIBLE (-4525 2575);
FORCEADD Q_CAP..1
(-4250 2725);
FORCEPROP 1 LAST LOCATION PC157_6
J 0
(-4200 2825);
DISPLAY 0.489362 (-4200 2825);
PAINT SKYBLUE (-4200 2825);
FORCEPROP 0 LAST $SEC 1
J 0
(-4200 2850);
DISPLAY 0.680851 (-4200 2850);
PAINT MONO (-4200 2850);
DISPLAY INVISIBLE (-4200 2850);
FORCEPROP 0 LAST CDS_SEC 1
J 0
(-4200 2850);
DISPLAY 1.021277 (-4200 2850);
DISPLAY INVISIBLE (-4200 2850);
FORCEPROP 1 LASTPIN (-4250 2825) $PN 1
J 0
(-4240 2805);
DISPLAY 0.489362 (-4240 2805);
PAINT MONO (-4240 2805);
FORCEPROP 1 LASTPIN (-4250 2625) $PN 2
J 0
(-4240 2605);
DISPLAY 0.489362 (-4240 2605);
PAINT MONO (-4240 2605);
FORCEPROP 1 LAST VALUE 22UF
J 0
(-4200 2775);
DISPLAY 0.489362 (-4200 2775);
PAINT SKYBLUE (-4200 2775);
FORCEPROP 1 LAST PACK_TYPE C0805
J 0
(-4200 2525);
DISPLAY 0.489362 (-4200 2525);
PAINT SKYBLUE (-4200 2525);
FORCEPROP 1 LAST MATERIAL X6S
J 0
(-4200 2625);
DISPLAY 0.489362 (-4200 2625);
PAINT SKYBLUE (-4200 2625);
FORCEPROP 1 LAST TOLERANCE 20%
J 0
(-4200 2675);
DISPLAY 0.489362 (-4200 2675);
PAINT SKYBLUE (-4200 2675);
FORCEPROP 1 LAST VOLTAGE 16V
J 0
(-4200 2725);
DISPLAY 0.489362 (-4200 2725);
PAINT SKYBLUE (-4200 2725);
FORCEPROP 2 LAST CDS_LIB pure_quanta
J 0
(-4250 2725);
DISPLAY INVISIBLE (-4250 2725);
FORCEPROP 1 LAST PATH I28
J 0
(-4200 2875);
DISPLAY 0.978723 (-4200 2875);
PAINT WHITE (-4200 2875);
DISPLAY INVISIBLE (-4200 2875);
FORCEPROP 1 LAST PART_NUMBER CH6223MEA01
J 0
(-4200 2575);
DISPLAY 0.489362 (-4200 2575);
PAINT SKYBLUE (-4200 2575);
DISPLAY INVISIBLE (-4200 2575);
FORCEADD Q_CAP..1
(-3925 2725);
FORCEPROP 1 LAST LOCATION PC158_6
J 0
(-3875 2825);
DISPLAY 0.489362 (-3875 2825);
PAINT SKYBLUE (-3875 2825);
FORCEPROP 0 LAST $SEC 1
J 0
(-3875 2850);
DISPLAY 0.680851 (-3875 2850);
PAINT MONO (-3875 2850);
DISPLAY INVISIBLE (-3875 2850);
FORCEPROP 0 LAST CDS_SEC 1
J 0
(-3875 2850);
DISPLAY 1.021277 (-3875 2850);
DISPLAY INVISIBLE (-3875 2850);
FORCEPROP 1 LASTPIN (-3925 2825) $PN 1
J 0
(-3915 2805);
DISPLAY 0.489362 (-3915 2805);
PAINT MONO (-3915 2805);
FORCEPROP 1 LASTPIN (-3925 2625) $PN 2
J 0
(-3915 2605);
DISPLAY 0.489362 (-3915 2605);
PAINT MONO (-3915 2605);
FORCEPROP 1 LAST PACK_TYPE C0805
J 0
(-3875 2525);
DISPLAY 0.489362 (-3875 2525);
PAINT SKYBLUE (-3875 2525);
FORCEPROP 1 LAST VALUE 22UF
J 0
(-3875 2775);
DISPLAY 0.489362 (-3875 2775);
PAINT SKYBLUE (-3875 2775);
FORCEPROP 1 LAST TOLERANCE 20%
J 0
(-3875 2675);
DISPLAY 0.489362 (-3875 2675);
PAINT SKYBLUE (-3875 2675);
FORCEPROP 1 LAST VOLTAGE 16V
J 0
(-3875 2725);
DISPLAY 0.489362 (-3875 2725);
PAINT SKYBLUE (-3875 2725);
FORCEPROP 1 LAST MATERIAL X6S
J 0
(-3875 2625);
DISPLAY 0.489362 (-3875 2625);
PAINT SKYBLUE (-3875 2625);
FORCEPROP 2 LAST CDS_LIB pure_quanta
J 0
(-3925 2725);
DISPLAY INVISIBLE (-3925 2725);
FORCEPROP 1 LAST PATH I29
J 0
(-3875 2875);
DISPLAY 0.978723 (-3875 2875);
PAINT WHITE (-3875 2875);
DISPLAY INVISIBLE (-3875 2875);
FORCEPROP 1 LAST PART_NUMBER CH6223MEA01
J 0
(-3875 2575);
DISPLAY 0.489362 (-3875 2575);
PAINT SKYBLUE (-3875 2575);
DISPLAY INVISIBLE (-3875 2575);
FORCEADD UNIVERSAL_GND..1
(-7525 1300);
FORCEPROP 3 LASTPIN (-7525 1350) SIG_NAME GND\g
J 0
(-7515 1360);
DISPLAY 0.659574 (-7515 1360);
PAINT MONO (-7515 1360);
DISPLAY INVISIBLE (-7515 1360);
FORCEPROP 2 LAST CDS_LIB pure_quanta_power
J 0
(-7525 1300);
DISPLAY INVISIBLE (-7525 1300);
FORCEPROP 1 LAST HDL_POWER GND
J 1
(-7500 1225);
DISPLAY 0.872340 (-7500 1225);
PAINT GREEN (-7500 1225);
DISPLAY INVISIBLE (-7500 1225);
FORCEPROP 1 LAST PATH I3
J 0
(-7450 1300);
DISPLAY 0.872340 (-7450 1300);
PAINT AQUA (-7450 1300);
DISPLAY INVISIBLE (-7450 1300);
FORCEADD UNIVERSAL_GND..1
(-4200 3725);
FORCEPROP 3 LASTPIN (-4200 3775) SIG_NAME GND\g
J 0
(-4190 3785);
DISPLAY 0.659574 (-4190 3785);
PAINT MONO (-4190 3785);
DISPLAY INVISIBLE (-4190 3785);
FORCEPROP 2 LAST CDS_LIB pure_quanta_power
J 0
(-4200 3725);
DISPLAY INVISIBLE (-4200 3725);
FORCEPROP 1 LAST HDL_POWER GND
J 1
(-4175 3650);
DISPLAY 0.872340 (-4175 3650);
PAINT GREEN (-4175 3650);
DISPLAY INVISIBLE (-4175 3650);
FORCEPROP 1 LAST PATH I30
J 0
(-4125 3725);
DISPLAY 0.872340 (-4125 3725);
PAINT AQUA (-4125 3725);
DISPLAY INVISIBLE (-4125 3725);
FORCEADD Q_RES..2
(-4200 3950);
FORCEPROP 1 LAST LOCATION PR501
J 0
(-4155 4075);
DISPLAY 0.489362 (-4155 4075);
PAINT SKYBLUE (-4155 4075);
FORCEPROP 0 LAST $SEC 1
J 0
(-4150 4125);
DISPLAY 0.680851 (-4150 4125);
PAINT MONO (-4150 4125);
DISPLAY INVISIBLE (-4150 4125);
FORCEPROP 0 LAST CDS_SEC 1
J 0
(-4150 4125);
DISPLAY 1.021277 (-4150 4125);
DISPLAY INVISIBLE (-4150 4125);
FORCEPROP 1 LASTPIN (-4200 4050) $PN 1
J 0
(-4195 4012);
DISPLAY 0.489362 (-4195 4012);
PAINT MONO (-4195 4012);
FORCEPROP 1 LASTPIN (-4200 3850) $PN 2
J 0
(-4195 3860);
DISPLAY 0.489362 (-4195 3860);
PAINT MONO (-4195 3860);
FORCEPROP 1 LAST TOLERANCE 1%
J 0
(-4155 3975);
DISPLAY 0.489362 (-4155 3975);
PAINT SKYBLUE (-4155 3975);
FORCEPROP 1 LAST PACK_TYPE 0402LF
J 0
(-4160 3775);
DISPLAY 0.489362 (-4160 3775);
PAINT SKYBLUE (-4160 3775);
FORCEPROP 1 LAST MATERIAL EMPTY
J 0
(-4160 3875);
DISPLAY 0.489362 (-4160 3875);
PAINT RED (-4160 3875);
FORCEPROP 1 LAST WATTAGE 1/8W
J 0
(-4160 3925);
DISPLAY 0.489362 (-4160 3925);
PAINT SKYBLUE (-4160 3925);
FORCEPROP 1 LAST VALUE 1.5
J 0
(-4155 4025);
DISPLAY 0.489362 (-4155 4025);
PAINT SKYBLUE (-4155 4025);
FORCEPROP 2 LAST CDS_LIB pure_quanta
J 0
(-4200 3950);
DISPLAY INVISIBLE (-4200 3950);
FORCEPROP 1 LAST PATH I31
J 0
(-4150 4125);
DISPLAY 0.978723 (-4150 4125);
PAINT WHITE (-4150 4125);
DISPLAY INVISIBLE (-4150 4125);
FORCEPROP 1 LAST PART_NUMBER CS-1504FB00
J 0
(-4160 3825);
DISPLAY 0.489362 (-4160 3825);
PAINT SKYBLUE (-4160 3825);
DISPLAY INVISIBLE (-4160 3825);
FORCEADD Q_RES..1
(-3625 3625);
FORCEPROP 1 LAST LOCATION PR355
J 0
(-3650 3675);
DISPLAY 0.489362 (-3650 3675);
PAINT SKYBLUE (-3650 3675);
FORCEPROP 0 LAST $SEC 1
J 0
(-3625 3700);
DISPLAY 0.680851 (-3625 3700);
PAINT MONO (-3625 3700);
DISPLAY INVISIBLE (-3625 3700);
FORCEPROP 0 LAST CDS_SEC 1
J 0
(-3625 3700);
DISPLAY 1.021277 (-3625 3700);
DISPLAY INVISIBLE (-3625 3700);
FORCEPROP 1 LASTPIN (-3725 3625) $PN 1
J 0
(-3713 3637);
DISPLAY 0.489362 (-3713 3637);
PAINT MONO (-3713 3637);
FORCEPROP 1 LASTPIN (-3525 3625) $PN 2
J 0
(-3563 3637);
DISPLAY 0.489362 (-3563 3637);
PAINT MONO (-3563 3637);
FORCEPROP 1 LAST WATTAGE 1/16W
J 0
(-3525 3575);
DISPLAY 0.489362 (-3525 3575);
PAINT SKYBLUE (-3525 3575);
FORCEPROP 1 LAST MATERIAL CHIP
J 0
(-3875 3525);
DISPLAY 0.489362 (-3875 3525);
PAINT SKYBLUE (-3875 3525);
FORCEPROP 1 LAST TOLERANCE 5%
J 0
(-3500 3650);
DISPLAY 0.489362 (-3500 3650);
PAINT SKYBLUE (-3500 3650);
FORCEPROP 1 LAST VALUE 0
J 2
(-3750 3650);
DISPLAY 0.489362 (-3750 3650);
PAINT SKYBLUE (-3750 3650);
FORCEPROP 1 LAST PACK_TYPE 0402LF
J 0
(-3525 3525);
DISPLAY 0.489362 (-3525 3525);
PAINT SKYBLUE (-3525 3525);
FORCEPROP 2 LAST CDS_LIB pure_quanta
J 0
(-3625 3625);
DISPLAY INVISIBLE (-3625 3625);
FORCEPROP 1 LAST PATH I32
J 0
(-3675 3775);
DISPLAY 0.978723 (-3675 3775);
PAINT WHITE (-3675 3775);
DISPLAY INVISIBLE (-3675 3775);
FORCEPROP 1 LAST PART_NUMBER CS00002JB13
J 0
(-3875 3575);
DISPLAY 0.489362 (-3875 3575);
PAINT SKYBLUE (-3875 3575);
DISPLAY INVISIBLE (-3875 3575);
FORCEADD Q_CAP..1
(-7525 4300);
FORCEPROP 1 LAST LOCATION PC566_5
J 0
(-7475 4400);
DISPLAY 0.489362 (-7475 4400);
PAINT SKYBLUE (-7475 4400);
FORCEPROP 0 LAST $SEC 1
J 0
(-7475 4425);
DISPLAY 0.680851 (-7475 4425);
PAINT MONO (-7475 4425);
DISPLAY INVISIBLE (-7475 4425);
FORCEPROP 0 LAST CDS_SEC 1
J 0
(-7475 4425);
DISPLAY 1.021277 (-7475 4425);
DISPLAY INVISIBLE (-7475 4425);
FORCEPROP 1 LASTPIN (-7525 4400) $PN 1
J 0
(-7515 4380);
DISPLAY 0.489362 (-7515 4380);
PAINT MONO (-7515 4380);
FORCEPROP 1 LASTPIN (-7525 4200) $PN 2
J 0
(-7515 4180);
DISPLAY 0.489362 (-7515 4180);
PAINT MONO (-7515 4180);
FORCEPROP 1 LAST PACK_TYPE 0402
J 0
(-7475 4100);
DISPLAY 0.489362 (-7475 4100);
PAINT SKYBLUE (-7475 4100);
FORCEPROP 1 LAST VOLTAGE 25V
J 0
(-7475 4300);
DISPLAY 0.489362 (-7475 4300);
PAINT SKYBLUE (-7475 4300);
FORCEPROP 1 LAST VALUE 0.1UF
J 0
(-7475 4350);
DISPLAY 0.489362 (-7475 4350);
PAINT SKYBLUE (-7475 4350);
FORCEPROP 1 LAST TOLERANCE 10%
J 0
(-7475 4250);
DISPLAY 0.489362 (-7475 4250);
PAINT SKYBLUE (-7475 4250);
FORCEPROP 1 LAST MATERIAL X7R
J 0
(-7475 4200);
DISPLAY 0.489362 (-7475 4200);
PAINT SKYBLUE (-7475 4200);
FORCEPROP 2 LAST CDS_LIB pure_quanta
J 0
(-7525 4300);
DISPLAY INVISIBLE (-7525 4300);
FORCEPROP 1 LAST PATH I33
J 0
(-7475 4450);
DISPLAY 0.978723 (-7475 4450);
PAINT WHITE (-7475 4450);
DISPLAY INVISIBLE (-7475 4450);
FORCEPROP 1 LAST PART_NUMBER CH4104K1B00
J 0
(-7475 4150);
DISPLAY 0.489362 (-7475 4150);
PAINT SKYBLUE (-7475 4150);
DISPLAY INVISIBLE (-7475 4150);
FORCEADD UNIVERSAL_GND..1
(-7200 4100);
FORCEPROP 3 LASTPIN (-7200 4150) SIG_NAME GND\g
J 0
(-7190 4160);
DISPLAY 0.659574 (-7190 4160);
PAINT MONO (-7190 4160);
DISPLAY INVISIBLE (-7190 4160);
FORCEPROP 2 LAST CDS_LIB pure_quanta_power
J 0
(-7200 4100);
DISPLAY INVISIBLE (-7200 4100);
FORCEPROP 1 LAST HDL_POWER GND
J 1
(-7175 4025);
DISPLAY 0.872340 (-7175 4025);
PAINT GREEN (-7175 4025);
DISPLAY INVISIBLE (-7175 4025);
FORCEPROP 1 LAST PATH I34
J 0
(-7125 4100);
DISPLAY 0.872340 (-7125 4100);
PAINT AQUA (-7125 4100);
DISPLAY INVISIBLE (-7125 4100);
FORCEADD OFFPAGE..2
R 2
(-6825 4075);
FORCEPROP 2 LAST $XR3 193 
J 0
(-7350 4039);
DISPLAY 0.638298 (-7350 4039);
PAINT MONO (-7350 4039);
FORCEPROP 2 LAST $XR2 196 
J 0
(-7230 4039);
DISPLAY 0.638298 (-7230 4039);
PAINT MONO (-7230 4039);
FORCEPROP 2 LAST $XR1 195 
J 0
(-7110 4039);
DISPLAY 0.638298 (-7110 4039);
PAINT MONO (-7110 4039);
FORCEPROP 2 LAST $XR0 194 
J 0
(-7110 4075);
DISPLAY 0.638298 (-7110 4075);
PAINT MONO (-7110 4075);
FORCEPROP 2 LAST CDS_LIB standard
J 0
(-6825 4075);
DISPLAY INVISIBLE (-6825 4075);
FORCEPROP 1 LAST OFFPAGE TRUE
J 2
(-7150 3950);
DISPLAY 0.872340 (-7150 3950);
PAINT GREEN (-7150 3950);
DISPLAY INVISIBLE (-7150 3950);
FORCEPROP 1 LAST COMMENT_BODY TRUE
J 2
(-6780 3980);
DISPLAY 0.872340 (-6780 3980);
PAINT GREEN (-6780 3980);
DISPLAY INVISIBLE (-6780 3980);
FORCEPROP 2 LAST PATH I35
J 0
(-7075 4125);
DISPLAY 0.680851 (-7075 4125);
DISPLAY INVISIBLE (-7075 4125);
FORCEADD Q_RES..1
(-6875 4275);
FORCEPROP 1 LAST LOCATION PR353
J 0
(-6900 4325);
DISPLAY 0.489362 (-6900 4325);
PAINT SKYBLUE (-6900 4325);
FORCEPROP 0 LAST $SEC 1
J 0
(-6875 4350);
DISPLAY 0.680851 (-6875 4350);
PAINT MONO (-6875 4350);
DISPLAY INVISIBLE (-6875 4350);
FORCEPROP 0 LAST CDS_SEC 1
J 0
(-6875 4350);
DISPLAY 1.021277 (-6875 4350);
DISPLAY INVISIBLE (-6875 4350);
FORCEPROP 1 LASTPIN (-6975 4275) $PN 1
J 0
(-6963 4287);
DISPLAY 0.489362 (-6963 4287);
PAINT MONO (-6963 4287);
FORCEPROP 1 LASTPIN (-6775 4275) $PN 2
J 0
(-6813 4287);
DISPLAY 0.489362 (-6813 4287);
PAINT MONO (-6813 4287);
FORCEPROP 1 LAST WATTAGE 1/16W
J 0
(-6775 4175);
DISPLAY 0.489362 (-6775 4175);
PAINT SKYBLUE (-6775 4175);
FORCEPROP 1 LAST MATERIAL EMPTY
J 0
(-7175 4175);
DISPLAY 0.489362 (-7175 4175);
PAINT RED (-7175 4175);
FORCEPROP 1 LAST TOLERANCE 1%
J 0
(-6750 4300);
DISPLAY 0.489362 (-6750 4300);
PAINT SKYBLUE (-6750 4300);
FORCEPROP 1 LAST VALUE 8.87K
J 2
(-7000 4300);
DISPLAY 0.489362 (-7000 4300);
PAINT SKYBLUE (-7000 4300);
FORCEPROP 1 LAST PACK_TYPE 0402LF
J 0
(-6775 4225);
DISPLAY 0.489362 (-6775 4225);
PAINT SKYBLUE (-6775 4225);
FORCEPROP 2 LAST CDS_LIB pure_quanta
J 0
(-6875 4275);
DISPLAY INVISIBLE (-6875 4275);
FORCEPROP 1 LAST PATH I36
J 0
(-6925 4425);
DISPLAY 0.978723 (-6925 4425);
PAINT WHITE (-6925 4425);
DISPLAY INVISIBLE (-6925 4425);
FORCEPROP 1 LAST PART_NUMBER CS28872FB01
J 0
(-7175 4225);
DISPLAY 0.489362 (-7175 4225);
PAINT SKYBLUE (-7175 4225);
DISPLAY INVISIBLE (-7175 4225);
FORCEADD UNIVERSAL_GND..1
(-7200 4725);
FORCEPROP 3 LASTPIN (-7200 4775) SIG_NAME GND\g
J 0
(-7190 4785);
DISPLAY 0.659574 (-7190 4785);
PAINT MONO (-7190 4785);
DISPLAY INVISIBLE (-7190 4785);
FORCEPROP 2 LAST CDS_LIB pure_quanta_power
J 0
(-7200 4725);
DISPLAY INVISIBLE (-7200 4725);
FORCEPROP 1 LAST HDL_POWER GND
J 1
(-7175 4650);
DISPLAY 0.872340 (-7175 4650);
PAINT GREEN (-7175 4650);
DISPLAY INVISIBLE (-7175 4650);
FORCEPROP 1 LAST PATH I37
J 0
(-7125 4725);
DISPLAY 0.872340 (-7125 4725);
PAINT AQUA (-7125 4725);
DISPLAY INVISIBLE (-7125 4725);
FORCEADD Q_CAP..1
(-7200 4925);
FORCEPROP 1 LAST LOCATION PC567
J 0
(-7150 5025);
DISPLAY 0.489362 (-7150 5025);
PAINT SKYBLUE (-7150 5025);
FORCEPROP 0 LAST $SEC 1
J 0
(-7150 5075);
DISPLAY 0.680851 (-7150 5075);
PAINT MONO (-7150 5075);
DISPLAY INVISIBLE (-7150 5075);
FORCEPROP 0 LAST CDS_SEC 1
J 0
(-7150 5075);
DISPLAY 1.021277 (-7150 5075);
DISPLAY INVISIBLE (-7150 5075);
FORCEPROP 1 LASTPIN (-7200 5025) $PN 1
J 0
(-7190 5005);
DISPLAY 0.489362 (-7190 5005);
PAINT MONO (-7190 5005);
FORCEPROP 1 LASTPIN (-7200 4825) $PN 2
J 0
(-7190 4805);
DISPLAY 0.489362 (-7190 4805);
PAINT MONO (-7190 4805);
FORCEPROP 1 LAST PACK_TYPE C0402
J 0
(-7150 4725);
DISPLAY 0.489362 (-7150 4725);
PAINT SKYBLUE (-7150 4725);
FORCEPROP 1 LAST VOLTAGE 10V
J 0
(-7150 4925);
DISPLAY 0.489362 (-7150 4925);
PAINT SKYBLUE (-7150 4925);
FORCEPROP 1 LAST VALUE 2.2UF
J 0
(-7150 4975);
DISPLAY 0.489362 (-7150 4975);
PAINT SKYBLUE (-7150 4975);
FORCEPROP 1 LAST TOLERANCE 10%
J 0
(-7150 4875);
DISPLAY 0.489362 (-7150 4875);
PAINT SKYBLUE (-7150 4875);
FORCEPROP 1 LAST MATERIAL X6S
J 0
(-7150 4825);
DISPLAY 0.489362 (-7150 4825);
PAINT SKYBLUE (-7150 4825);
FORCEPROP 2 LAST CDS_LIB pure_quanta
J 0
(-7200 4925);
DISPLAY INVISIBLE (-7200 4925);
FORCEPROP 1 LAST PATH I38
J 0
(-7150 5075);
DISPLAY 0.978723 (-7150 5075);
PAINT WHITE (-7150 5075);
DISPLAY INVISIBLE (-7150 5075);
FORCEPROP 1 LAST PART_NUMBER CH5222KEB01
J 0
(-7150 4775);
DISPLAY 0.489362 (-7150 4775);
PAINT SKYBLUE (-7150 4775);
DISPLAY INVISIBLE (-7150 4775);
FORCEADD OFFPAGE..2
R 2
(-6850 4575);
FORCEPROP 2 LAST $XR0 193 
J 0
(-7135 4575);
DISPLAY 0.638298 (-7135 4575);
PAINT MONO (-7135 4575);
FORCEPROP 2 LAST CDS_LIB standard
J 2
(-6850 4575);
DISPLAY INVISIBLE (-6850 4575);
FORCEPROP 1 LAST OFFPAGE TRUE
J 2
(-7175 4450);
DISPLAY 0.872340 (-7175 4450);
PAINT GREEN (-7175 4450);
DISPLAY INVISIBLE (-7175 4450);
FORCEPROP 1 LAST COMMENT_BODY TRUE
J 2
(-6805 4480);
DISPLAY 0.872340 (-6805 4480);
PAINT GREEN (-6805 4480);
DISPLAY INVISIBLE (-6805 4480);
FORCEPROP 2 LAST PATH I39
J 0
(-7100 4625);
DISPLAY 0.680851 (-7100 4625);
DISPLAY INVISIBLE (-7100 4625);
FORCEADD Q_CAP..1
(-7525 1575);
FORCEPROP 1 LAST LOCATION PC150_6
J 0
(-7475 1675);
DISPLAY 0.489362 (-7475 1675);
PAINT SKYBLUE (-7475 1675);
FORCEPROP 0 LAST $SEC 1
J 0
(-7475 1700);
DISPLAY 0.680851 (-7475 1700);
PAINT MONO (-7475 1700);
DISPLAY INVISIBLE (-7475 1700);
FORCEPROP 0 LAST CDS_SEC 1
J 0
(-7475 1700);
DISPLAY 1.021277 (-7475 1700);
DISPLAY INVISIBLE (-7475 1700);
FORCEPROP 1 LASTPIN (-7525 1675) $PN 1
J 0
(-7515 1655);
DISPLAY 0.489362 (-7515 1655);
PAINT MONO (-7515 1655);
FORCEPROP 1 LASTPIN (-7525 1475) $PN 2
J 0
(-7515 1455);
DISPLAY 0.489362 (-7515 1455);
PAINT MONO (-7515 1455);
FORCEPROP 1 LAST PACK_TYPE 0402
J 0
(-7475 1375);
DISPLAY 0.489362 (-7475 1375);
PAINT SKYBLUE (-7475 1375);
FORCEPROP 1 LAST VOLTAGE 25V
J 0
(-7475 1575);
DISPLAY 0.489362 (-7475 1575);
PAINT SKYBLUE (-7475 1575);
FORCEPROP 1 LAST VALUE 0.1UF
J 0
(-7475 1625);
DISPLAY 0.489362 (-7475 1625);
PAINT SKYBLUE (-7475 1625);
FORCEPROP 1 LAST TOLERANCE 10%
J 0
(-7475 1525);
DISPLAY 0.489362 (-7475 1525);
PAINT SKYBLUE (-7475 1525);
FORCEPROP 1 LAST MATERIAL X7R
J 0
(-7475 1475);
DISPLAY 0.489362 (-7475 1475);
PAINT SKYBLUE (-7475 1475);
FORCEPROP 2 LAST CDS_LIB pure_quanta
J 0
(-7525 1575);
DISPLAY INVISIBLE (-7525 1575);
FORCEPROP 1 LAST PATH I4
J 0
(-7475 1725);
DISPLAY 0.978723 (-7475 1725);
PAINT WHITE (-7475 1725);
DISPLAY INVISIBLE (-7475 1725);
FORCEPROP 1 LAST PART_NUMBER CH4104K1B00
J 0
(-7475 1425);
DISPLAY 0.489362 (-7475 1425);
PAINT SKYBLUE (-7475 1425);
DISPLAY INVISIBLE (-7475 1425);
FORCEADD Q_RES..2
(-7200 5425);
FORCEPROP 1 LAST LOCATION PR352
J 0
(-7155 5525);
DISPLAY 0.489362 (-7155 5525);
PAINT SKYBLUE (-7155 5525);
FORCEPROP 0 LAST $SEC 1
J 0
(-7150 5600);
DISPLAY 0.680851 (-7150 5600);
PAINT MONO (-7150 5600);
DISPLAY INVISIBLE (-7150 5600);
FORCEPROP 0 LAST CDS_SEC 1
J 0
(-7150 5600);
DISPLAY 1.021277 (-7150 5600);
DISPLAY INVISIBLE (-7150 5600);
FORCEPROP 1 LASTPIN (-7200 5525) $PN 1
J 0
(-7195 5487);
DISPLAY 0.489362 (-7195 5487);
PAINT MONO (-7195 5487);
FORCEPROP 1 LASTPIN (-7200 5325) $PN 2
J 0
(-7195 5335);
DISPLAY 0.489362 (-7195 5335);
PAINT MONO (-7195 5335);
FORCEPROP 1 LAST MATERIAL CHIP
J 0
(-7150 5325);
DISPLAY 0.489362 (-7150 5325);
PAINT SKYBLUE (-7150 5325);
FORCEPROP 1 LAST TOLERANCE 1%
J 0
(-7150 5425);
DISPLAY 0.489362 (-7150 5425);
PAINT SKYBLUE (-7150 5425);
FORCEPROP 1 LAST VALUE 2.2
J 0
(-7150 5475);
DISPLAY 0.489362 (-7150 5475);
PAINT SKYBLUE (-7150 5475);
FORCEPROP 1 LAST WATTAGE 1/16W
J 0
(-7150 5375);
DISPLAY 0.489362 (-7150 5375);
PAINT SKYBLUE (-7150 5375);
FORCEPROP 1 LAST PACK_TYPE 0402LF
J 0
(-7150 5225);
DISPLAY 0.489362 (-7150 5225);
PAINT SKYBLUE (-7150 5225);
FORCEPROP 2 LAST CDS_LIB pure_quanta
J 0
(-7200 5425);
DISPLAY INVISIBLE (-7200 5425);
FORCEPROP 1 LAST PATH I40
J 0
(-7150 5600);
DISPLAY 0.978723 (-7150 5600);
PAINT WHITE (-7150 5600);
DISPLAY INVISIBLE (-7150 5600);
FORCEPROP 1 LAST PART_NUMBER CS-2202FB01
J 0
(-7150 5275);
DISPLAY 0.489362 (-7150 5275);
PAINT SKYBLUE (-7150 5275);
DISPLAY INVISIBLE (-7150 5275);
FORCEADD UNIVERSAL_GND..1
(-6850 5175);
FORCEPROP 3 LASTPIN (-6850 5225) SIG_NAME GND\g
J 0
(-6840 5235);
DISPLAY 0.659574 (-6840 5235);
PAINT MONO (-6840 5235);
DISPLAY INVISIBLE (-6840 5235);
FORCEPROP 2 LAST CDS_LIB pure_quanta_power
J 0
(-6850 5175);
DISPLAY INVISIBLE (-6850 5175);
FORCEPROP 1 LAST HDL_POWER GND
J 1
(-6825 5100);
DISPLAY 0.872340 (-6825 5100);
PAINT GREEN (-6825 5100);
DISPLAY INVISIBLE (-6825 5100);
FORCEPROP 1 LAST PATH I41
J 0
(-6775 5175);
DISPLAY 0.872340 (-6775 5175);
PAINT AQUA (-6775 5175);
DISPLAY INVISIBLE (-6775 5175);
FORCEADD Q_CAP..1
(-6850 5425);
FORCEPROP 1 LAST LOCATION PC568_C0P0_5
J 0
(-6800 5525);
DISPLAY 0.489362 (-6800 5525);
PAINT SKYBLUE (-6800 5525);
FORCEPROP 0 LAST $SEC 1
J 0
(-6800 5575);
DISPLAY 0.680851 (-6800 5575);
PAINT MONO (-6800 5575);
DISPLAY INVISIBLE (-6800 5575);
FORCEPROP 0 LAST CDS_SEC 1
J 0
(-6800 5575);
DISPLAY 1.021277 (-6800 5575);
DISPLAY INVISIBLE (-6800 5575);
FORCEPROP 1 LASTPIN (-6850 5525) $PN 1
J 0
(-6840 5505);
DISPLAY 0.489362 (-6840 5505);
PAINT MONO (-6840 5505);
FORCEPROP 1 LASTPIN (-6850 5325) $PN 2
J 0
(-6840 5305);
DISPLAY 0.489362 (-6840 5305);
PAINT MONO (-6840 5305);
FORCEPROP 1 LAST PACK_TYPE C0402
J 0
(-6800 5225);
DISPLAY 0.489362 (-6800 5225);
PAINT SKYBLUE (-6800 5225);
FORCEPROP 1 LAST VOLTAGE 10V
J 0
(-6800 5425);
DISPLAY 0.489362 (-6800 5425);
PAINT SKYBLUE (-6800 5425);
FORCEPROP 1 LAST VALUE 2.2UF
J 0
(-6800 5475);
DISPLAY 0.489362 (-6800 5475);
PAINT SKYBLUE (-6800 5475);
FORCEPROP 1 LAST TOLERANCE 10%
J 0
(-6800 5375);
DISPLAY 0.489362 (-6800 5375);
PAINT SKYBLUE (-6800 5375);
FORCEPROP 1 LAST MATERIAL X6S
J 0
(-6800 5325);
DISPLAY 0.489362 (-6800 5325);
PAINT SKYBLUE (-6800 5325);
FORCEPROP 2 LAST CDS_LIB pure_quanta
J 0
(-6850 5425);
DISPLAY INVISIBLE (-6850 5425);
FORCEPROP 1 LAST PATH I42
J 0
(-6800 5575);
DISPLAY 0.978723 (-6800 5575);
PAINT WHITE (-6800 5575);
DISPLAY INVISIBLE (-6800 5575);
FORCEPROP 1 LAST PART_NUMBER CH5222KEB01
J 0
(-6800 5275);
DISPLAY 0.489362 (-6800 5275);
PAINT SKYBLUE (-6800 5275);
DISPLAY INVISIBLE (-6800 5275);
FORCEADD VCC_CORE..1
(-7200 5825);
FORCEPROP 3 LASTPIN (-7200 5775) SIG_NAME PVDDCR_CPU0_P0_PVCC\g
J 0
(-7190 5785);
DISPLAY 0.659574 (-7190 5785);
PAINT MONO (-7190 5785);
DISPLAY INVISIBLE (-7190 5785);
FORCEPROP 1 LAST HDL_POWER PVDDCR_CPU0_P0_PVCC
J 1
(-7200 5875);
DISPLAY 0.489362 (-7200 5875);
PAINT GREEN (-7200 5875);
FORCEPROP 2 LAST CDS_LIB pure_quanta_power
J 0
(-7200 5825);
DISPLAY INVISIBLE (-7200 5825);
FORCEPROP 1 LAST PATH I43
J 0
(-7150 5850);
DISPLAY 0.872340 (-7150 5850);
PAINT AQUA (-7150 5850);
DISPLAY INVISIBLE (-7150 5850);
FORCEADD Q_CAP..1
(-4950 5450);
FORCEPROP 1 LAST LOCATION PC570_5
J 0
(-4900 5550);
DISPLAY 0.489362 (-4900 5550);
PAINT SKYBLUE (-4900 5550);
FORCEPROP 0 LAST $SEC 1
J 0
(-4900 5600);
DISPLAY 0.680851 (-4900 5600);
PAINT MONO (-4900 5600);
DISPLAY INVISIBLE (-4900 5600);
FORCEPROP 0 LAST CDS_SEC 1
J 0
(-4900 5600);
DISPLAY 1.021277 (-4900 5600);
DISPLAY INVISIBLE (-4900 5600);
FORCEPROP 1 LASTPIN (-4950 5550) $PN 1
J 0
(-4940 5530);
DISPLAY 0.489362 (-4940 5530);
PAINT MONO (-4940 5530);
FORCEPROP 1 LASTPIN (-4950 5350) $PN 2
J 0
(-4940 5330);
DISPLAY 0.489362 (-4940 5330);
PAINT MONO (-4940 5330);
FORCEPROP 1 LAST PACK_TYPE 0402
J 0
(-4900 5250);
DISPLAY 0.489362 (-4900 5250);
PAINT SKYBLUE (-4900 5250);
FORCEPROP 1 LAST TOLERANCE 10%
J 0
(-4900 5400);
DISPLAY 0.489362 (-4900 5400);
PAINT SKYBLUE (-4900 5400);
FORCEPROP 1 LAST VOLTAGE 25V
J 0
(-4900 5450);
DISPLAY 0.489362 (-4900 5450);
PAINT SKYBLUE (-4900 5450);
FORCEPROP 1 LAST MATERIAL X7R
J 0
(-4900 5350);
DISPLAY 0.489362 (-4900 5350);
PAINT SKYBLUE (-4900 5350);
FORCEPROP 1 LAST VALUE 0.1UF
J 0
(-4900 5500);
DISPLAY 0.489362 (-4900 5500);
PAINT SKYBLUE (-4900 5500);
FORCEPROP 2 LAST CDS_LIB pure_quanta
J 0
(-4950 5450);
DISPLAY INVISIBLE (-4950 5450);
FORCEPROP 1 LAST PATH I44
J 0
(-4900 5600);
DISPLAY 0.978723 (-4900 5600);
PAINT WHITE (-4900 5600);
DISPLAY INVISIBLE (-4900 5600);
FORCEPROP 1 LAST PART_NUMBER CH4104K1B00
J 0
(-4900 5300);
DISPLAY 0.489362 (-4900 5300);
PAINT SKYBLUE (-4900 5300);
DISPLAY INVISIBLE (-4900 5300);
FORCEADD Q_RES..1
(-4275 4925);
FORCEPROP 1 LAST LOCATION PR354
J 0
(-4300 4975);
DISPLAY 0.489362 (-4300 4975);
PAINT SKYBLUE (-4300 4975);
FORCEPROP 0 LAST $SEC 1
J 0
(-4250 5000);
DISPLAY 0.680851 (-4250 5000);
PAINT MONO (-4250 5000);
DISPLAY INVISIBLE (-4250 5000);
FORCEPROP 0 LAST CDS_SEC 1
J 0
(-4250 5000);
DISPLAY 1.021277 (-4250 5000);
DISPLAY INVISIBLE (-4250 5000);
FORCEPROP 1 LASTPIN (-4375 4925) $PN 1
J 0
(-4363 4937);
DISPLAY 0.489362 (-4363 4937);
PAINT MONO (-4363 4937);
FORCEPROP 1 LASTPIN (-4175 4925) $PN 2
J 0
(-4213 4937);
DISPLAY 0.489362 (-4213 4937);
PAINT MONO (-4213 4937);
FORCEPROP 1 LAST WATTAGE 1/16W
J 0
(-4175 4875);
DISPLAY 0.489362 (-4175 4875);
PAINT SKYBLUE (-4175 4875);
FORCEPROP 1 LAST TOLERANCE 1%
J 0
(-4175 4950);
DISPLAY 0.489362 (-4175 4950);
PAINT SKYBLUE (-4175 4950);
FORCEPROP 1 LAST PACK_TYPE 0402LF
J 0
(-4175 4825);
DISPLAY 0.489362 (-4175 4825);
PAINT SKYBLUE (-4175 4825);
FORCEPROP 1 LAST VALUE 5.6
J 2
(-4375 4950);
DISPLAY 0.489362 (-4375 4950);
PAINT SKYBLUE (-4375 4950);
FORCEPROP 1 LAST MATERIAL CHIP
J 0
(-4525 4825);
DISPLAY 0.489362 (-4525 4825);
PAINT SKYBLUE (-4525 4825);
FORCEPROP 2 LAST CDS_LIB pure_quanta
J 0
(-4275 4925);
DISPLAY INVISIBLE (-4275 4925);
FORCEPROP 1 LAST PATH I45
J 0
(-4325 5075);
DISPLAY 0.978723 (-4325 5075);
PAINT WHITE (-4325 5075);
DISPLAY INVISIBLE (-4325 5075);
FORCEPROP 1 LAST PART_NUMBER CS-5602FB01
J 0
(-4525 4875);
DISPLAY 0.489362 (-4525 4875);
PAINT SKYBLUE (-4525 4875);
DISPLAY INVISIBLE (-4525 4875);
FORCEADD Q_CAP..1
(-4200 4400);
FORCEPROP 1 LAST LOCATION PC184
J 0
(-4150 4500);
DISPLAY 0.489362 (-4150 4500);
PAINT SKYBLUE (-4150 4500);
FORCEPROP 0 LAST $SEC 1
J 0
(-4150 4550);
DISPLAY 0.680851 (-4150 4550);
PAINT MONO (-4150 4550);
DISPLAY INVISIBLE (-4150 4550);
FORCEPROP 0 LAST CDS_SEC 1
J 0
(-4150 4550);
DISPLAY 1.021277 (-4150 4550);
DISPLAY INVISIBLE (-4150 4550);
FORCEPROP 1 LASTPIN (-4200 4500) $PN 1
J 0
(-4190 4480);
DISPLAY 0.489362 (-4190 4480);
PAINT MONO (-4190 4480);
FORCEPROP 1 LASTPIN (-4200 4300) $PN 2
J 0
(-4190 4280);
DISPLAY 0.489362 (-4190 4280);
PAINT MONO (-4190 4280);
FORCEPROP 1 LAST VALUE 560PF
J 0
(-4150 4450);
DISPLAY 0.489362 (-4150 4450);
PAINT SKYBLUE (-4150 4450);
FORCEPROP 1 LAST TOLERANCE 10%
J 0
(-4150 4350);
DISPLAY 0.489362 (-4150 4350);
PAINT SKYBLUE (-4150 4350);
FORCEPROP 1 LAST MATERIAL EMPTY
J 0
(-4150 4300);
DISPLAY 0.489362 (-4150 4300);
PAINT RED (-4150 4300);
FORCEPROP 1 LAST VOLTAGE 50V
J 0
(-4150 4400);
DISPLAY 0.489362 (-4150 4400);
PAINT SKYBLUE (-4150 4400);
FORCEPROP 1 LAST PACK_TYPE C0402
J 0
(-4150 4200);
DISPLAY 0.489362 (-4150 4200);
PAINT SKYBLUE (-4150 4200);
FORCEPROP 2 LAST CDS_LIB pure_quanta
J 0
(-4200 4400);
DISPLAY INVISIBLE (-4200 4400);
FORCEPROP 1 LAST PATH I46
J 0
(-4150 4550);
DISPLAY 0.978723 (-4150 4550);
PAINT WHITE (-4150 4550);
DISPLAY INVISIBLE (-4150 4550);
FORCEPROP 1 LAST PART_NUMBER CH1566K1B09
J 0
(-4150 4250);
DISPLAY 0.489362 (-4150 4250);
PAINT SKYBLUE (-4150 4250);
DISPLAY INVISIBLE (-4150 4250);
FORCEADD Q_CAP..1
(-4575 5450);
FORCEPROP 1 LAST LOCATION PC569_5
J 0
(-4525 5550);
DISPLAY 0.489362 (-4525 5550);
PAINT SKYBLUE (-4525 5550);
FORCEPROP 0 LAST $SEC 1
J 0
(-4525 5575);
DISPLAY 0.680851 (-4525 5575);
PAINT MONO (-4525 5575);
DISPLAY INVISIBLE (-4525 5575);
FORCEPROP 0 LAST CDS_SEC 1
J 0
(-4525 5575);
DISPLAY 1.021277 (-4525 5575);
DISPLAY INVISIBLE (-4525 5575);
FORCEPROP 1 LASTPIN (-4575 5550) $PN 1
J 0
(-4565 5530);
DISPLAY 0.489362 (-4565 5530);
PAINT MONO (-4565 5530);
FORCEPROP 1 LASTPIN (-4575 5350) $PN 2
J 0
(-4565 5330);
DISPLAY 0.489362 (-4565 5330);
PAINT MONO (-4565 5330);
FORCEPROP 1 LAST MATERIAL X6S
J 0
(-4525 5350);
DISPLAY 0.489362 (-4525 5350);
PAINT SKYBLUE (-4525 5350);
FORCEPROP 1 LAST VOLTAGE 25V
J 0
(-4525 5450);
DISPLAY 0.489362 (-4525 5450);
PAINT SKYBLUE (-4525 5450);
FORCEPROP 1 LAST VALUE 1UF
J 0
(-4525 5500);
DISPLAY 0.489362 (-4525 5500);
PAINT SKYBLUE (-4525 5500);
FORCEPROP 1 LAST PACK_TYPE C0402
J 0
(-4525 5250);
DISPLAY 0.489362 (-4525 5250);
PAINT SKYBLUE (-4525 5250);
FORCEPROP 1 LAST TOLERANCE 10%
J 0
(-4525 5400);
DISPLAY 0.489362 (-4525 5400);
PAINT SKYBLUE (-4525 5400);
FORCEPROP 2 LAST CDS_LIB pure_quanta
J 0
(-4575 5450);
DISPLAY INVISIBLE (-4575 5450);
FORCEPROP 1 LAST PATH I47
J 0
(-4525 5600);
DISPLAY 0.978723 (-4525 5600);
PAINT WHITE (-4525 5600);
DISPLAY INVISIBLE (-4525 5600);
FORCEPROP 1 LAST PART_NUMBER CH5104KEB02
J 0
(-4525 5300);
DISPLAY 0.489362 (-4525 5300);
PAINT SKYBLUE (-4525 5300);
DISPLAY INVISIBLE (-4525 5300);
FORCEADD Q_CAP..1
(-4250 5450);
FORCEPROP 1 LAST LOCATION PC571_5
J 0
(-4200 5550);
DISPLAY 0.489362 (-4200 5550);
PAINT SKYBLUE (-4200 5550);
FORCEPROP 0 LAST $SEC 1
J 0
(-4200 5575);
DISPLAY 0.680851 (-4200 5575);
PAINT MONO (-4200 5575);
DISPLAY INVISIBLE (-4200 5575);
FORCEPROP 0 LAST CDS_SEC 1
J 0
(-4200 5575);
DISPLAY 1.021277 (-4200 5575);
DISPLAY INVISIBLE (-4200 5575);
FORCEPROP 1 LASTPIN (-4250 5550) $PN 1
J 0
(-4240 5530);
DISPLAY 0.489362 (-4240 5530);
PAINT MONO (-4240 5530);
FORCEPROP 1 LASTPIN (-4250 5350) $PN 2
J 0
(-4240 5330);
DISPLAY 0.489362 (-4240 5330);
PAINT MONO (-4240 5330);
FORCEPROP 1 LAST PACK_TYPE C0805
J 0
(-4200 5250);
DISPLAY 0.489362 (-4200 5250);
PAINT SKYBLUE (-4200 5250);
FORCEPROP 1 LAST VALUE 22UF
J 0
(-4200 5500);
DISPLAY 0.489362 (-4200 5500);
PAINT SKYBLUE (-4200 5500);
FORCEPROP 1 LAST VOLTAGE 16V
J 0
(-4200 5450);
DISPLAY 0.489362 (-4200 5450);
PAINT SKYBLUE (-4200 5450);
FORCEPROP 1 LAST TOLERANCE 20%
J 0
(-4200 5400);
DISPLAY 0.489362 (-4200 5400);
PAINT SKYBLUE (-4200 5400);
FORCEPROP 1 LAST MATERIAL X6S
J 0
(-4200 5350);
DISPLAY 0.489362 (-4200 5350);
PAINT SKYBLUE (-4200 5350);
FORCEPROP 2 LAST CDS_LIB pure_quanta
J 0
(-4250 5450);
DISPLAY INVISIBLE (-4250 5450);
FORCEPROP 1 LAST PATH I48
J 0
(-4200 5600);
DISPLAY 0.978723 (-4200 5600);
PAINT WHITE (-4200 5600);
DISPLAY INVISIBLE (-4200 5600);
FORCEPROP 1 LAST PART_NUMBER CH6223MEA01
J 0
(-4200 5300);
DISPLAY 0.489362 (-4200 5300);
PAINT SKYBLUE (-4200 5300);
DISPLAY INVISIBLE (-4200 5300);
FORCEADD Q_CAP..1
(-3900 5450);
FORCEPROP 1 LAST LOCATION PC572_5
J 0
(-3850 5550);
DISPLAY 0.489362 (-3850 5550);
PAINT SKYBLUE (-3850 5550);
FORCEPROP 0 LAST $SEC 1
J 0
(-3850 5575);
DISPLAY 0.680851 (-3850 5575);
PAINT MONO (-3850 5575);
DISPLAY INVISIBLE (-3850 5575);
FORCEPROP 0 LAST CDS_SEC 1
J 0
(-3850 5575);
DISPLAY 1.021277 (-3850 5575);
DISPLAY INVISIBLE (-3850 5575);
FORCEPROP 1 LASTPIN (-3900 5550) $PN 1
J 0
(-3890 5530);
DISPLAY 0.489362 (-3890 5530);
PAINT MONO (-3890 5530);
FORCEPROP 1 LASTPIN (-3900 5350) $PN 2
J 0
(-3890 5330);
DISPLAY 0.489362 (-3890 5330);
PAINT MONO (-3890 5330);
FORCEPROP 1 LAST VALUE 22UF
J 0
(-3850 5500);
DISPLAY 0.489362 (-3850 5500);
PAINT SKYBLUE (-3850 5500);
FORCEPROP 1 LAST MATERIAL X6S
J 0
(-3850 5350);
DISPLAY 0.489362 (-3850 5350);
PAINT SKYBLUE (-3850 5350);
FORCEPROP 1 LAST VOLTAGE 16V
J 0
(-3850 5450);
DISPLAY 0.489362 (-3850 5450);
PAINT SKYBLUE (-3850 5450);
FORCEPROP 1 LAST TOLERANCE 20%
J 0
(-3850 5400);
DISPLAY 0.489362 (-3850 5400);
PAINT SKYBLUE (-3850 5400);
FORCEPROP 1 LAST PACK_TYPE C0805
J 0
(-3850 5250);
DISPLAY 0.489362 (-3850 5250);
PAINT SKYBLUE (-3850 5250);
FORCEPROP 2 LAST CDS_LIB pure_quanta
J 0
(-3900 5450);
DISPLAY INVISIBLE (-3900 5450);
FORCEPROP 1 LAST PATH I49
J 0
(-3850 5600);
DISPLAY 0.978723 (-3850 5600);
PAINT WHITE (-3850 5600);
DISPLAY INVISIBLE (-3850 5600);
FORCEPROP 1 LAST PART_NUMBER CH6223MEA01
J 0
(-3850 5300);
DISPLAY 0.489362 (-3850 5300);
PAINT SKYBLUE (-3850 5300);
DISPLAY INVISIBLE (-3850 5300);
FORCEADD UNIVERSAL_GND..1
(-7200 1375);
FORCEPROP 3 LASTPIN (-7200 1425) SIG_NAME GND\g
J 0
(-7190 1435);
DISPLAY 0.659574 (-7190 1435);
PAINT MONO (-7190 1435);
DISPLAY INVISIBLE (-7190 1435);
FORCEPROP 2 LAST CDS_LIB pure_quanta_power
J 0
(-7200 1375);
DISPLAY INVISIBLE (-7200 1375);
FORCEPROP 1 LAST HDL_POWER GND
J 1
(-7175 1300);
DISPLAY 0.872340 (-7175 1300);
PAINT GREEN (-7175 1300);
DISPLAY INVISIBLE (-7175 1300);
FORCEPROP 1 LAST PATH I5
J 0
(-7125 1375);
DISPLAY 0.872340 (-7125 1375);
PAINT AQUA (-7125 1375);
DISPLAY INVISIBLE (-7125 1375);
FORCEADD UNIVERSAL_GND..1
(-3625 1500);
FORCEPROP 3 LASTPIN (-3625 1550) SIG_NAME GND\g
J 0
(-3615 1560);
DISPLAY 0.659574 (-3615 1560);
PAINT MONO (-3615 1560);
DISPLAY INVISIBLE (-3615 1560);
FORCEPROP 2 LAST CDS_LIB pure_quanta_power
J 0
(-3625 1500);
DISPLAY INVISIBLE (-3625 1500);
FORCEPROP 1 LAST HDL_POWER GND
J 1
(-3600 1425);
DISPLAY 0.872340 (-3600 1425);
PAINT GREEN (-3600 1425);
DISPLAY INVISIBLE (-3600 1425);
FORCEPROP 1 LAST PATH I50
J 0
(-3550 1500);
DISPLAY 0.872340 (-3550 1500);
PAINT AQUA (-3550 1500);
DISPLAY INVISIBLE (-3550 1500);
FORCEADD Q_INDUCTOR..1
(-3450 1625);
FORCEPROP 1 LAST LOCATION PL50
J 0
(-3600 1775);
DISPLAY 0.489362 (-3600 1775);
PAINT SKYBLUE (-3600 1775);
FORCEPROP 0 LAST $SEC 1
J 0
(-3600 1800);
DISPLAY 0.680851 (-3600 1800);
PAINT MONO (-3600 1800);
DISPLAY INVISIBLE (-3600 1800);
FORCEPROP 0 LAST CDS_SEC 1
J 0
(-3600 1800);
DISPLAY 0.680851 (-3600 1800);
DISPLAY INVISIBLE (-3600 1800);
FORCEPROP 0 LASTPIN (-3550 1600) $PN 1
J 2
(-3560 1610);
DISPLAY 0.489362 (-3560 1610);
PAINT MONO (-3560 1610);
FORCEPROP 0 LASTPIN (-3350 1600) $PN 2
J 0
(-3340 1610);
DISPLAY 0.489362 (-3340 1610);
PAINT MONO (-3340 1610);
FORCEPROP 2 LAST PACK_TYPE SMLF
J 0
(-3600 1725);
DISPLAY 0.489362 (-3600 1725);
PAINT SKYBLUE (-3600 1725);
FORCEPROP 2 LAST VALUE 120NH/69A
J 0
(-3600 1750);
DISPLAY 0.489362 (-3600 1750);
PAINT SKYBLUE (-3600 1750);
FORCEPROP 1 LAST MATERIAL IND
J 0
(-3600 1675);
DISPLAY 0.489362 (-3600 1675);
PAINT SKYBLUE (-3600 1675);
FORCEPROP 2 LAST CDS_LIB pure_quanta
J 0
(-3450 1625);
DISPLAY INVISIBLE (-3450 1625);
FORCEPROP 1 LAST NEEDS_NO_SIZE TRUE
J 0
(-3450 1625);
DISPLAY 0.468085 (-3450 1625);
PAINT GREEN (-3450 1625);
DISPLAY INVISIBLE (-3450 1625);
FORCEPROP 1 LAST PATH I51
J 0
(-3375 1680);
DISPLAY 0.723404 (-3375 1680);
PAINT GREEN (-3375 1680);
DISPLAY INVISIBLE (-3375 1680);
FORCEPROP 1 LAST PART_NUMBER CV+12^0EZ03
J 0
(-3600 1700);
DISPLAY 0.489362 (-3600 1700);
PAINT SKYBLUE (-3600 1700);
DISPLAY INVISIBLE (-3600 1700);
FORCEADD Q_INDUCTOR4P_14..1
(-2475 1725);
FORCEPROP 1 LAST LOCATION PL70
J 0
(-2700 1980);
DISPLAY 0.489362 (-2700 1980);
PAINT SKYBLUE (-2700 1980);
FORCEPROP 0 LAST $SEC 1
J 0
(-2700 2125);
DISPLAY 0.680851 (-2700 2125);
PAINT MONO (-2700 2125);
DISPLAY INVISIBLE (-2700 2125);
FORCEPROP 0 LAST CDS_SEC 1
J 0
(-2700 2125);
DISPLAY 1.021277 (-2700 2125);
DISPLAY INVISIBLE (-2700 2125);
FORCEPROP 0 LASTPIN (-2875 1850) $PN 1
J 2
(-2885 1860);
DISPLAY 0.489362 (-2885 1860);
PAINT MONO (-2885 1860);
FORCEPROP 0 LASTPIN (-2875 1600) $PN 2
J 2
(-2885 1610);
DISPLAY 0.489362 (-2885 1610);
PAINT MONO (-2885 1610);
FORCEPROP 0 LASTPIN (-2075 1600) $PN 3
J 0
(-2065 1610);
DISPLAY 0.489362 (-2065 1610);
PAINT MONO (-2065 1610);
FORCEPROP 0 LASTPIN (-2075 1850) $PN 4
J 0
(-2065 1860);
DISPLAY 0.489362 (-2065 1860);
PAINT MONO (-2065 1860);
FORCEPROP 2 LAST VALUE 150NH
J 0
(-2700 2025);
DISPLAY 0.489362 (-2700 2025);
PAINT SKYBLUE (-2700 2025);
FORCEPROP 2 LAST PART_TYPE SMLF
J 0
(-2700 2075);
DISPLAY 1.021277 (-2700 2075);
FORCEPROP 1 LAST MATERIAL IND
J 0
(-2700 1935);
DISPLAY 0.489362 (-2700 1935);
PAINT SKYBLUE (-2700 1935);
FORCEPROP 2 LAST CDS_LIB pure_quanta
J 0
(-2475 1725);
DISPLAY INVISIBLE (-2475 1725);
FORCEPROP 1 LAST NEEDS_NO_SIZE TRUE
J 0
(-2475 1725);
DISPLAY 0.468085 (-2475 1725);
PAINT GREEN (-2475 1725);
DISPLAY INVISIBLE (-2475 1725);
FORCEPROP 1 LAST PATH I52
J 0
(-2275 1880);
DISPLAY 0.723404 (-2275 1880);
PAINT GREEN (-2275 1880);
DISPLAY INVISIBLE (-2275 1880);
FORCEPROP 1 LAST PART_NUMBER CV+15^0TZ04
J 0
(-2700 1885);
DISPLAY 0.489362 (-2700 1885);
PAINT SKYBLUE (-2700 1885);
DISPLAY INVISIBLE (-2700 1885);
FORCEADD UNIVERSAL_GND..1
(-3625 2375);
FORCEPROP 3 LASTPIN (-3625 2425) SIG_NAME GND\g
J 0
(-3615 2435);
DISPLAY 0.659574 (-3615 2435);
PAINT MONO (-3615 2435);
DISPLAY INVISIBLE (-3615 2435);
FORCEPROP 2 LAST CDS_LIB pure_quanta_power
J 0
(-3625 2375);
DISPLAY INVISIBLE (-3625 2375);
FORCEPROP 1 LAST HDL_POWER GND
J 1
(-3600 2300);
DISPLAY 0.872340 (-3600 2300);
PAINT GREEN (-3600 2300);
DISPLAY INVISIBLE (-3600 2300);
FORCEPROP 1 LAST PATH I53
J 0
(-3550 2375);
DISPLAY 0.872340 (-3550 2375);
PAINT AQUA (-3550 2375);
DISPLAY INVISIBLE (-3550 2375);
FORCEADD Q_CAP..1
(-3275 2075);
FORCEPROP 1 LAST LOCATION PC161
J 0
(-3225 2200);
DISPLAY 0.489362 (-3225 2200);
PAINT SKYBLUE (-3225 2200);
FORCEPROP 0 LAST $SEC 1
J 0
(-3225 2225);
DISPLAY 0.680851 (-3225 2225);
PAINT MONO (-3225 2225);
DISPLAY INVISIBLE (-3225 2225);
FORCEPROP 0 LAST CDS_SEC 1
J 0
(-3225 2225);
DISPLAY 1.021277 (-3225 2225);
DISPLAY INVISIBLE (-3225 2225);
FORCEPROP 1 LASTPIN (-3275 2175) $PN 1
J 0
(-3265 2155);
DISPLAY 0.489362 (-3265 2155);
PAINT MONO (-3265 2155);
FORCEPROP 1 LASTPIN (-3275 1975) $PN 2
J 0
(-3265 1955);
DISPLAY 0.489362 (-3265 1955);
PAINT MONO (-3265 1955);
FORCEPROP 1 LAST VOLTAGE 16V
J 0
(-3225 2100);
DISPLAY 0.489362 (-3225 2100);
PAINT SKYBLUE (-3225 2100);
FORCEPROP 1 LAST VALUE 0.22UF
J 0
(-3225 2150);
DISPLAY 0.489362 (-3225 2150);
PAINT SKYBLUE (-3225 2150);
FORCEPROP 1 LAST TOLERANCE 10%
J 0
(-3225 2050);
DISPLAY 0.489362 (-3225 2050);
PAINT SKYBLUE (-3225 2050);
FORCEPROP 1 LAST MATERIAL X7R
J 0
(-3225 2000);
DISPLAY 0.489362 (-3225 2000);
PAINT SKYBLUE (-3225 2000);
FORCEPROP 1 LAST PACK_TYPE 0402
J 0
(-3225 1900);
DISPLAY 0.489362 (-3225 1900);
PAINT SKYBLUE (-3225 1900);
FORCEPROP 2 LAST CDS_LIB pure_quanta
J 0
(-3275 2075);
DISPLAY INVISIBLE (-3275 2075);
FORCEPROP 1 LAST PATH I54
J 0
(-3225 2225);
DISPLAY 0.978723 (-3225 2225);
PAINT WHITE (-3225 2225);
DISPLAY INVISIBLE (-3225 2225);
FORCEPROP 1 LAST PART_NUMBER CH4223K1B00
J 0
(-3225 1950);
DISPLAY 0.489362 (-3225 1950);
PAINT SKYBLUE (-3225 1950);
DISPLAY INVISIBLE (-3225 1950);
FORCEADD Q_CAP..1
(-3625 2725);
FORCEPROP 1 LAST LOCATION PC159_6
J 0
(-3575 2825);
DISPLAY 0.489362 (-3575 2825);
PAINT SKYBLUE (-3575 2825);
FORCEPROP 0 LAST $SEC 1
J 0
(-3575 2850);
DISPLAY 0.680851 (-3575 2850);
PAINT MONO (-3575 2850);
DISPLAY INVISIBLE (-3575 2850);
FORCEPROP 0 LAST CDS_SEC 1
J 0
(-3575 2850);
DISPLAY 1.021277 (-3575 2850);
DISPLAY INVISIBLE (-3575 2850);
FORCEPROP 1 LASTPIN (-3625 2825) $PN 1
J 0
(-3615 2805);
DISPLAY 0.489362 (-3615 2805);
PAINT MONO (-3615 2805);
FORCEPROP 1 LASTPIN (-3625 2625) $PN 2
J 0
(-3615 2605);
DISPLAY 0.489362 (-3615 2605);
PAINT MONO (-3615 2605);
FORCEPROP 1 LAST TOLERANCE 20%
J 0
(-3575 2675);
DISPLAY 0.489362 (-3575 2675);
PAINT SKYBLUE (-3575 2675);
FORCEPROP 1 LAST VALUE 22UF
J 0
(-3575 2775);
DISPLAY 0.489362 (-3575 2775);
PAINT SKYBLUE (-3575 2775);
FORCEPROP 1 LAST VOLTAGE 16V
J 0
(-3575 2725);
DISPLAY 0.489362 (-3575 2725);
PAINT SKYBLUE (-3575 2725);
FORCEPROP 1 LAST MATERIAL X6S
J 0
(-3575 2625);
DISPLAY 0.489362 (-3575 2625);
PAINT SKYBLUE (-3575 2625);
FORCEPROP 1 LAST PACK_TYPE C0805
J 0
(-3575 2525);
DISPLAY 0.489362 (-3575 2525);
PAINT SKYBLUE (-3575 2525);
FORCEPROP 2 LAST CDS_LIB pure_quanta
J 0
(-3625 2725);
DISPLAY INVISIBLE (-3625 2725);
FORCEPROP 1 LAST PATH I55
J 0
(-3575 2875);
DISPLAY 0.978723 (-3575 2875);
PAINT WHITE (-3575 2875);
DISPLAY INVISIBLE (-3575 2875);
FORCEPROP 1 LAST PART_NUMBER CH6223MEA01
J 0
(-3575 2575);
DISPLAY 0.489362 (-3575 2575);
PAINT SKYBLUE (-3575 2575);
DISPLAY INVISIBLE (-3575 2575);
FORCEADD VCC_CORE..1
(-3625 3025);
FORCEPROP 3 LASTPIN (-3625 2975) SIG_NAME SW_P12V_AUX_PVDDCR_CPU0_P0_FLT\g
J 0
(-3615 2985);
DISPLAY 0.659574 (-3615 2985);
PAINT MONO (-3615 2985);
DISPLAY INVISIBLE (-3615 2985);
FORCEPROP 1 LAST HDL_POWER SW_P12V_AUX_PVDDCR_CPU0_P0_FLT
J 1
(-3625 3075);
DISPLAY 0.489362 (-3625 3075);
PAINT GREEN (-3625 3075);
FORCEPROP 2 LAST CDS_LIB pure_quanta_power
J 0
(-3625 3025);
DISPLAY INVISIBLE (-3625 3025);
FORCEPROP 1 LAST PATH I56
J 0
(-3575 3050);
DISPLAY 0.872340 (-3575 3050);
PAINT AQUA (-3575 3050);
DISPLAY INVISIBLE (-3575 3050);
FORCEADD OFFPAGE..3
(-1550 1600);
FORCEPROP 2 LAST $XR0 196 
J 0
(-1276 1600);
DISPLAY 0.638298 (-1276 1600);
PAINT MONO (-1276 1600);
FORCEPROP 2 LAST CDS_LIB standard
J 2
(-1550 1600);
DISPLAY INVISIBLE (-1550 1600);
FORCEPROP 1 LAST OFFPAGE TRUE
J 0
(-1225 1475);
DISPLAY 0.872340 (-1225 1475);
PAINT GREEN (-1225 1475);
DISPLAY INVISIBLE (-1225 1475);
FORCEPROP 1 LAST COMMENT_BODY TRUE
J 0
(-1600 1500);
DISPLAY 0.872340 (-1600 1500);
PAINT GREEN (-1600 1500);
DISPLAY INVISIBLE (-1600 1500);
FORCEPROP 2 LAST PATH I57
J 0
(-1275 1650);
DISPLAY 0.680851 (-1275 1650);
DISPLAY INVISIBLE (-1275 1650);
FORCEADD UNIVERSAL_GND..1
(-650 1325);
FORCEPROP 3 LASTPIN (-650 1375) SIG_NAME GND\g
J 0
(-640 1385);
DISPLAY 0.659574 (-640 1385);
PAINT MONO (-640 1385);
DISPLAY INVISIBLE (-640 1385);
FORCEPROP 2 LAST CDS_LIB pure_quanta_power
J 0
(-650 1325);
DISPLAY INVISIBLE (-650 1325);
FORCEPROP 1 LAST HDL_POWER GND
J 1
(-625 1250);
DISPLAY 0.872340 (-625 1250);
PAINT GREEN (-625 1250);
DISPLAY INVISIBLE (-625 1250);
FORCEPROP 1 LAST PATH I58
J 0
(-575 1325);
DISPLAY 0.872340 (-575 1325);
PAINT AQUA (-575 1325);
DISPLAY INVISIBLE (-575 1325);
FORCEADD Q_CAP..1
(-1075 1675);
FORCEPROP 1 LAST LOCATION PC163_6
J 0
(-1025 1775);
DISPLAY 0.489362 (-1025 1775);
PAINT SKYBLUE (-1025 1775);
FORCEPROP 0 LAST $SEC 1
J 0
(-1025 1800);
DISPLAY 0.680851 (-1025 1800);
PAINT MONO (-1025 1800);
DISPLAY INVISIBLE (-1025 1800);
FORCEPROP 0 LAST CDS_SEC 1
J 0
(-1025 1800);
DISPLAY 1.021277 (-1025 1800);
DISPLAY INVISIBLE (-1025 1800);
FORCEPROP 1 LASTPIN (-1075 1775) $PN 1
J 0
(-1065 1755);
DISPLAY 0.489362 (-1065 1755);
PAINT MONO (-1065 1755);
FORCEPROP 1 LASTPIN (-1075 1575) $PN 2
J 0
(-1065 1555);
DISPLAY 0.489362 (-1065 1555);
PAINT MONO (-1065 1555);
FORCEPROP 1 LAST PACK_TYPE C0805
J 0
(-1025 1475);
DISPLAY 0.489362 (-1025 1475);
PAINT SKYBLUE (-1025 1475);
FORCEPROP 1 LAST MATERIAL X6S
J 0
(-1025 1575);
DISPLAY 0.489362 (-1025 1575);
PAINT SKYBLUE (-1025 1575);
FORCEPROP 1 LAST TOLERANCE 20%
J 0
(-1025 1625);
DISPLAY 0.489362 (-1025 1625);
PAINT SKYBLUE (-1025 1625);
FORCEPROP 1 LAST VALUE 22UF
J 0
(-1025 1725);
DISPLAY 0.489362 (-1025 1725);
PAINT SKYBLUE (-1025 1725);
FORCEPROP 1 LAST VOLTAGE 4V
J 0
(-1025 1675);
DISPLAY 0.489362 (-1025 1675);
PAINT SKYBLUE (-1025 1675);
FORCEPROP 2 LAST CDS_LIB pure_quanta
J 0
(-1075 1675);
DISPLAY INVISIBLE (-1075 1675);
FORCEPROP 1 LAST PATH I59
J 0
(-1025 1825);
DISPLAY 0.978723 (-1025 1825);
PAINT WHITE (-1025 1825);
DISPLAY INVISIBLE (-1025 1825);
FORCEPROP 1 LAST PART_NUMBER CH622KMEA03
J 0
(-1025 1525);
DISPLAY 0.489362 (-1025 1525);
PAINT SKYBLUE (-1025 1525);
DISPLAY INVISIBLE (-1025 1525);
FORCEADD OFFPAGE..1
(-6800 1250);
FORCEPROP 2 LAST $XR0 193 
J 0
(-7082 1250);
DISPLAY 0.638298 (-7082 1250);
PAINT MONO (-7082 1250);
FORCEPROP 2 LAST CDS_LIB standard
J 2
(-6800 1250);
DISPLAY INVISIBLE (-6800 1250);
FORCEPROP 1 LAST OFFPAGE TRUE
J 0
(-6475 1125);
DISPLAY 0.872340 (-6475 1125);
PAINT GREEN (-6475 1125);
DISPLAY INVISIBLE (-6475 1125);
FORCEPROP 1 LAST COMMENT_BODY TRUE
J 0
(-6675 1150);
DISPLAY 0.872340 (-6675 1150);
PAINT GREEN (-6675 1150);
DISPLAY INVISIBLE (-6675 1150);
FORCEPROP 2 LAST PATH I6
J 0
(-7050 1300);
DISPLAY 0.680851 (-7050 1300);
DISPLAY INVISIBLE (-7050 1300);
FORCEADD Q_CAP..1
(-650 1675);
FORCEPROP 1 LAST LOCATION PC166_6
J 0
(-600 1775);
DISPLAY 0.489362 (-600 1775);
PAINT SKYBLUE (-600 1775);
FORCEPROP 0 LAST $SEC 1
J 0
(-600 1800);
DISPLAY 0.680851 (-600 1800);
PAINT MONO (-600 1800);
DISPLAY INVISIBLE (-600 1800);
FORCEPROP 0 LAST CDS_SEC 1
J 0
(-600 1800);
DISPLAY 1.021277 (-600 1800);
DISPLAY INVISIBLE (-600 1800);
FORCEPROP 1 LASTPIN (-650 1775) $PN 1
J 0
(-640 1755);
DISPLAY 0.489362 (-640 1755);
PAINT MONO (-640 1755);
FORCEPROP 1 LASTPIN (-650 1575) $PN 2
J 0
(-640 1555);
DISPLAY 0.489362 (-640 1555);
PAINT MONO (-640 1555);
FORCEPROP 1 LAST PACK_TYPE C0805
J 0
(-600 1475);
DISPLAY 0.489362 (-600 1475);
PAINT SKYBLUE (-600 1475);
FORCEPROP 1 LAST MATERIAL X6S
J 0
(-600 1575);
DISPLAY 0.489362 (-600 1575);
PAINT SKYBLUE (-600 1575);
FORCEPROP 1 LAST TOLERANCE 20%
J 0
(-600 1625);
DISPLAY 0.489362 (-600 1625);
PAINT SKYBLUE (-600 1625);
FORCEPROP 1 LAST VALUE 22UF
J 0
(-600 1725);
DISPLAY 0.489362 (-600 1725);
PAINT SKYBLUE (-600 1725);
FORCEPROP 1 LAST VOLTAGE 4V
J 0
(-600 1675);
DISPLAY 0.489362 (-600 1675);
PAINT SKYBLUE (-600 1675);
FORCEPROP 2 LAST CDS_LIB pure_quanta
J 0
(-650 1675);
DISPLAY INVISIBLE (-650 1675);
FORCEPROP 1 LAST PATH I60
J 0
(-600 1825);
DISPLAY 0.978723 (-600 1825);
PAINT WHITE (-600 1825);
DISPLAY INVISIBLE (-600 1825);
FORCEPROP 1 LAST PART_NUMBER CH622KMEA03
J 0
(-600 1525);
DISPLAY 0.489362 (-600 1525);
PAINT SKYBLUE (-600 1525);
DISPLAY INVISIBLE (-600 1525);
FORCEADD VCC_CORE..1
(-650 2000);
FORCEPROP 3 LASTPIN (-650 1950) SIG_NAME PVDDCR_CPU0_P0\g
J 0
(-640 1960);
DISPLAY 0.659574 (-640 1960);
PAINT MONO (-640 1960);
DISPLAY INVISIBLE (-640 1960);
FORCEPROP 1 LAST HDL_POWER PVDDCR_CPU0_P0
J 1
(-650 2050);
DISPLAY 0.489362 (-650 2050);
PAINT GREEN (-650 2050);
FORCEPROP 2 LAST CDS_LIB pure_quanta_power
J 0
(-650 2000);
DISPLAY INVISIBLE (-650 2000);
FORCEPROP 1 LAST PATH I61
J 0
(-600 2025);
DISPLAY 0.872340 (-600 2025);
PAINT AQUA (-600 2025);
DISPLAY INVISIBLE (-600 2025);
FORCEADD OFFPAGE..3
R 2
(-3375 4325);
FORCEPROP 2 LAST $XR0 196 
J 0
(-3655 4325);
DISPLAY 0.638298 (-3655 4325);
PAINT MONO (-3655 4325);
FORCEPROP 2 LAST CDS_LIB standard
J 2
(-3375 4325);
DISPLAY INVISIBLE (-3375 4325);
FORCEPROP 1 LAST OFFPAGE TRUE
J 2
(-3700 4200);
DISPLAY 0.872340 (-3700 4200);
PAINT GREEN (-3700 4200);
DISPLAY INVISIBLE (-3700 4200);
FORCEPROP 1 LAST COMMENT_BODY TRUE
J 2
(-3325 4225);
DISPLAY 0.872340 (-3325 4225);
PAINT GREEN (-3325 4225);
DISPLAY INVISIBLE (-3325 4225);
FORCEPROP 2 LAST PATH I62
J 0
(-3675 4375);
DISPLAY 0.680851 (-3675 4375);
DISPLAY INVISIBLE (-3675 4375);
FORCEADD Q_CAP..1
(-3275 4800);
FORCEPROP 1 LAST LOCATION PC574
J 0
(-3225 4925);
DISPLAY 0.489362 (-3225 4925);
PAINT SKYBLUE (-3225 4925);
FORCEPROP 0 LAST $SEC 1
J 0
(-3225 4950);
DISPLAY 0.680851 (-3225 4950);
PAINT MONO (-3225 4950);
DISPLAY INVISIBLE (-3225 4950);
FORCEPROP 0 LAST CDS_SEC 1
J 0
(-3225 4950);
DISPLAY 1.021277 (-3225 4950);
DISPLAY INVISIBLE (-3225 4950);
FORCEPROP 1 LASTPIN (-3275 4900) $PN 1
J 0
(-3265 4880);
DISPLAY 0.489362 (-3265 4880);
PAINT MONO (-3265 4880);
FORCEPROP 1 LASTPIN (-3275 4700) $PN 2
J 0
(-3265 4680);
DISPLAY 0.489362 (-3265 4680);
PAINT MONO (-3265 4680);
FORCEPROP 1 LAST MATERIAL X7R
J 0
(-3225 4725);
DISPLAY 0.489362 (-3225 4725);
PAINT SKYBLUE (-3225 4725);
FORCEPROP 1 LAST PACK_TYPE 0402
J 0
(-3225 4625);
DISPLAY 0.489362 (-3225 4625);
PAINT SKYBLUE (-3225 4625);
FORCEPROP 1 LAST VALUE 0.22UF
J 0
(-3225 4875);
DISPLAY 0.489362 (-3225 4875);
PAINT SKYBLUE (-3225 4875);
FORCEPROP 1 LAST VOLTAGE 16V
J 0
(-3225 4825);
DISPLAY 0.489362 (-3225 4825);
PAINT SKYBLUE (-3225 4825);
FORCEPROP 1 LAST TOLERANCE 10%
J 0
(-3225 4775);
DISPLAY 0.489362 (-3225 4775);
PAINT SKYBLUE (-3225 4775);
FORCEPROP 2 LAST CDS_LIB pure_quanta
J 0
(-3275 4800);
DISPLAY INVISIBLE (-3275 4800);
FORCEPROP 1 LAST PATH I63
J 0
(-3225 4950);
DISPLAY 0.978723 (-3225 4950);
PAINT WHITE (-3225 4950);
DISPLAY INVISIBLE (-3225 4950);
FORCEPROP 1 LAST PART_NUMBER CH4223K1B00
J 0
(-3225 4675);
DISPLAY 0.489362 (-3225 4675);
PAINT SKYBLUE (-3225 4675);
DISPLAY INVISIBLE (-3225 4675);
FORCEADD Q_INDUCTOR4P_14..1
(-2475 4450);
FORCEPROP 1 LAST LOCATION PL61
J 0
(-2700 4705);
DISPLAY 0.489362 (-2700 4705);
PAINT SKYBLUE (-2700 4705);
FORCEPROP 0 LAST $SEC 1
J 0
(-2700 4850);
DISPLAY 0.680851 (-2700 4850);
PAINT MONO (-2700 4850);
DISPLAY INVISIBLE (-2700 4850);
FORCEPROP 0 LAST CDS_SEC 1
J 0
(-2700 4850);
DISPLAY 1.021277 (-2700 4850);
DISPLAY INVISIBLE (-2700 4850);
FORCEPROP 0 LASTPIN (-2875 4575) $PN 1
J 2
(-2885 4585);
DISPLAY 0.489362 (-2885 4585);
PAINT MONO (-2885 4585);
FORCEPROP 0 LASTPIN (-2875 4325) $PN 2
J 2
(-2885 4335);
DISPLAY 0.489362 (-2885 4335);
PAINT MONO (-2885 4335);
FORCEPROP 0 LASTPIN (-2075 4325) $PN 3
J 0
(-2065 4335);
DISPLAY 0.489362 (-2065 4335);
PAINT MONO (-2065 4335);
FORCEPROP 0 LASTPIN (-2075 4575) $PN 4
J 0
(-2065 4585);
DISPLAY 0.489362 (-2065 4585);
PAINT MONO (-2065 4585);
FORCEPROP 2 LAST PART_TYPE SMLF
J 0
(-2700 4800);
DISPLAY 1.021277 (-2700 4800);
FORCEPROP 2 LAST VALUE 150NH
J 0
(-2700 4750);
DISPLAY 0.489362 (-2700 4750);
PAINT SKYBLUE (-2700 4750);
FORCEPROP 1 LAST MATERIAL IND
J 0
(-2700 4660);
DISPLAY 0.489362 (-2700 4660);
PAINT SKYBLUE (-2700 4660);
FORCEPROP 1 LAST NEEDS_NO_SIZE TRUE
J 0
(-2475 4450);
DISPLAY 0.468085 (-2475 4450);
PAINT GREEN (-2475 4450);
DISPLAY INVISIBLE (-2475 4450);
FORCEPROP 2 LAST CDS_LIB pure_quanta
J 0
(-2475 4450);
DISPLAY INVISIBLE (-2475 4450);
FORCEPROP 1 LAST PATH I64
J 0
(-2275 4605);
DISPLAY 0.723404 (-2275 4605);
PAINT GREEN (-2275 4605);
DISPLAY INVISIBLE (-2275 4605);
FORCEPROP 1 LAST PART_NUMBER CV+15^0TZ04
J 0
(-2700 4610);
DISPLAY 0.489362 (-2700 4610);
PAINT SKYBLUE (-2700 4610);
DISPLAY INVISIBLE (-2700 4610);
FORCEADD UNIVERSAL_GND..1
(-3550 5100);
FORCEPROP 3 LASTPIN (-3550 5150) SIG_NAME GND\g
J 0
(-3540 5160);
DISPLAY 0.659574 (-3540 5160);
PAINT MONO (-3540 5160);
DISPLAY INVISIBLE (-3540 5160);
FORCEPROP 2 LAST CDS_LIB pure_quanta_power
J 0
(-3550 5100);
DISPLAY INVISIBLE (-3550 5100);
FORCEPROP 1 LAST HDL_POWER GND
J 1
(-3525 5025);
DISPLAY 0.872340 (-3525 5025);
PAINT GREEN (-3525 5025);
DISPLAY INVISIBLE (-3525 5025);
FORCEPROP 1 LAST PATH I65
J 0
(-3475 5100);
DISPLAY 0.872340 (-3475 5100);
PAINT AQUA (-3475 5100);
DISPLAY INVISIBLE (-3475 5100);
FORCEADD Q_CAP..1
(-3550 5450);
FORCEPROP 1 LAST LOCATION PC573_5
J 0
(-3500 5550);
DISPLAY 0.489362 (-3500 5550);
PAINT SKYBLUE (-3500 5550);
FORCEPROP 0 LAST $SEC 1
J 0
(-3500 5575);
DISPLAY 0.680851 (-3500 5575);
PAINT MONO (-3500 5575);
DISPLAY INVISIBLE (-3500 5575);
FORCEPROP 0 LAST CDS_SEC 1
J 0
(-3500 5575);
DISPLAY 1.021277 (-3500 5575);
DISPLAY INVISIBLE (-3500 5575);
FORCEPROP 1 LASTPIN (-3550 5550) $PN 1
J 0
(-3540 5530);
DISPLAY 0.489362 (-3540 5530);
PAINT MONO (-3540 5530);
FORCEPROP 1 LASTPIN (-3550 5350) $PN 2
J 0
(-3540 5330);
DISPLAY 0.489362 (-3540 5330);
PAINT MONO (-3540 5330);
FORCEPROP 1 LAST MATERIAL X6S
J 0
(-3500 5350);
DISPLAY 0.489362 (-3500 5350);
PAINT SKYBLUE (-3500 5350);
FORCEPROP 1 LAST VOLTAGE 16V
J 0
(-3500 5450);
DISPLAY 0.489362 (-3500 5450);
PAINT SKYBLUE (-3500 5450);
FORCEPROP 1 LAST VALUE 22UF
J 0
(-3500 5500);
DISPLAY 0.489362 (-3500 5500);
PAINT SKYBLUE (-3500 5500);
FORCEPROP 1 LAST TOLERANCE 20%
J 0
(-3500 5400);
DISPLAY 0.489362 (-3500 5400);
PAINT SKYBLUE (-3500 5400);
FORCEPROP 1 LAST PACK_TYPE C0805
J 0
(-3500 5250);
DISPLAY 0.489362 (-3500 5250);
PAINT SKYBLUE (-3500 5250);
FORCEPROP 2 LAST CDS_LIB pure_quanta
J 0
(-3550 5450);
DISPLAY INVISIBLE (-3550 5450);
FORCEPROP 1 LAST PATH I66
J 0
(-3500 5600);
DISPLAY 0.978723 (-3500 5600);
PAINT WHITE (-3500 5600);
DISPLAY INVISIBLE (-3500 5600);
FORCEPROP 1 LAST PART_NUMBER CH6223MEA01
J 0
(-3500 5300);
DISPLAY 0.489362 (-3500 5300);
PAINT SKYBLUE (-3500 5300);
DISPLAY INVISIBLE (-3500 5300);
FORCEADD VCC_CORE..1
(-3550 5750);
FORCEPROP 3 LASTPIN (-3550 5700) SIG_NAME SW_P12V_AUX_PVDDCR_CPU0_P0_FLT\g
J 0
(-3540 5710);
DISPLAY 0.659574 (-3540 5710);
PAINT MONO (-3540 5710);
DISPLAY INVISIBLE (-3540 5710);
FORCEPROP 1 LAST HDL_POWER SW_P12V_AUX_PVDDCR_CPU0_P0_FLT
J 1
(-3550 5800);
DISPLAY 0.489362 (-3550 5800);
PAINT GREEN (-3550 5800);
FORCEPROP 2 LAST CDS_LIB pure_quanta_power
J 0
(-3550 5750);
DISPLAY INVISIBLE (-3550 5750);
FORCEPROP 1 LAST PATH I67
J 0
(-3500 5775);
DISPLAY 0.872340 (-3500 5775);
PAINT AQUA (-3500 5775);
DISPLAY INVISIBLE (-3500 5775);
FORCEADD OFFPAGE..3
(-1575 4325);
FORCEPROP 2 LAST $XR0 194 
J 0
(-1271 4325);
DISPLAY 0.638298 (-1271 4325);
PAINT MONO (-1271 4325);
FORCEPROP 2 LAST CDS_LIB standard
J 2
(-1575 4325);
DISPLAY INVISIBLE (-1575 4325);
FORCEPROP 1 LAST OFFPAGE TRUE
J 0
(-1250 4200);
DISPLAY 0.872340 (-1250 4200);
PAINT GREEN (-1250 4200);
DISPLAY INVISIBLE (-1250 4200);
FORCEPROP 1 LAST COMMENT_BODY TRUE
J 0
(-1625 4225);
DISPLAY 0.872340 (-1625 4225);
PAINT GREEN (-1625 4225);
DISPLAY INVISIBLE (-1625 4225);
FORCEPROP 2 LAST PATH I68
J 0
(-1250 4375);
DISPLAY 0.680851 (-1250 4375);
DISPLAY INVISIBLE (-1250 4375);
FORCEADD Q_CAP..1
(-1075 4400);
FORCEPROP 1 LAST LOCATION PC575_5
J 0
(-1025 4500);
DISPLAY 0.489362 (-1025 4500);
PAINT SKYBLUE (-1025 4500);
FORCEPROP 0 LAST $SEC 1
J 0
(-1025 4525);
DISPLAY 0.680851 (-1025 4525);
PAINT MONO (-1025 4525);
DISPLAY INVISIBLE (-1025 4525);
FORCEPROP 0 LAST CDS_SEC 1
J 0
(-1025 4525);
DISPLAY 1.021277 (-1025 4525);
DISPLAY INVISIBLE (-1025 4525);
FORCEPROP 1 LASTPIN (-1075 4500) $PN 1
J 0
(-1065 4480);
DISPLAY 0.489362 (-1065 4480);
PAINT MONO (-1065 4480);
FORCEPROP 1 LASTPIN (-1075 4300) $PN 2
J 0
(-1065 4280);
DISPLAY 0.489362 (-1065 4280);
PAINT MONO (-1065 4280);
FORCEPROP 1 LAST PACK_TYPE C0805
J 0
(-1025 4200);
DISPLAY 0.489362 (-1025 4200);
PAINT SKYBLUE (-1025 4200);
FORCEPROP 1 LAST MATERIAL X6S
J 0
(-1025 4300);
DISPLAY 0.489362 (-1025 4300);
PAINT SKYBLUE (-1025 4300);
FORCEPROP 1 LAST TOLERANCE 20%
J 0
(-1025 4350);
DISPLAY 0.489362 (-1025 4350);
PAINT SKYBLUE (-1025 4350);
FORCEPROP 1 LAST VALUE 22UF
J 0
(-1025 4450);
DISPLAY 0.489362 (-1025 4450);
PAINT SKYBLUE (-1025 4450);
FORCEPROP 1 LAST VOLTAGE 4V
J 0
(-1025 4400);
DISPLAY 0.489362 (-1025 4400);
PAINT SKYBLUE (-1025 4400);
FORCEPROP 2 LAST CDS_LIB pure_quanta
J 0
(-1075 4400);
DISPLAY INVISIBLE (-1075 4400);
FORCEPROP 1 LAST PATH I69
J 0
(-1025 4550);
DISPLAY 0.978723 (-1025 4550);
PAINT WHITE (-1025 4550);
DISPLAY INVISIBLE (-1025 4550);
FORCEPROP 1 LAST PART_NUMBER CH622KMEA03
J 0
(-1025 4250);
DISPLAY 0.489362 (-1025 4250);
PAINT SKYBLUE (-1025 4250);
DISPLAY INVISIBLE (-1025 4250);
FORCEADD OFFPAGE..2
R 2
(-6825 1350);
FORCEPROP 2 LAST $XR3 193 
J 0
(-7350 1314);
DISPLAY 0.638298 (-7350 1314);
PAINT MONO (-7350 1314);
FORCEPROP 2 LAST $XR2 196 
J 0
(-7230 1314);
DISPLAY 0.638298 (-7230 1314);
PAINT MONO (-7230 1314);
FORCEPROP 2 LAST $XR1 195 
J 0
(-7110 1314);
DISPLAY 0.638298 (-7110 1314);
PAINT MONO (-7110 1314);
FORCEPROP 2 LAST $XR0 194 
J 0
(-7110 1350);
DISPLAY 0.638298 (-7110 1350);
PAINT MONO (-7110 1350);
FORCEPROP 2 LAST CDS_LIB standard
J 0
(-6825 1350);
DISPLAY INVISIBLE (-6825 1350);
FORCEPROP 1 LAST OFFPAGE TRUE
J 2
(-7150 1225);
DISPLAY 0.872340 (-7150 1225);
PAINT GREEN (-7150 1225);
DISPLAY INVISIBLE (-7150 1225);
FORCEPROP 1 LAST COMMENT_BODY TRUE
J 2
(-6780 1255);
DISPLAY 0.872340 (-6780 1255);
PAINT GREEN (-6780 1255);
DISPLAY INVISIBLE (-6780 1255);
FORCEPROP 2 LAST PATH I7
J 0
(-7075 1400);
DISPLAY 0.680851 (-7075 1400);
DISPLAY INVISIBLE (-7075 1400);
FORCEADD UNIVERSAL_GND..1
(-650 4050);
FORCEPROP 3 LASTPIN (-650 4100) SIG_NAME GND\g
J 0
(-640 4110);
DISPLAY 0.659574 (-640 4110);
PAINT MONO (-640 4110);
DISPLAY INVISIBLE (-640 4110);
FORCEPROP 2 LAST CDS_LIB pure_quanta_power
J 0
(-650 4050);
DISPLAY INVISIBLE (-650 4050);
FORCEPROP 1 LAST HDL_POWER GND
J 1
(-625 3975);
DISPLAY 0.872340 (-625 3975);
PAINT GREEN (-625 3975);
DISPLAY INVISIBLE (-625 3975);
FORCEPROP 1 LAST PATH I70
J 0
(-575 4050);
DISPLAY 0.872340 (-575 4050);
PAINT AQUA (-575 4050);
DISPLAY INVISIBLE (-575 4050);
FORCEADD Q_CAP..1
(-650 4400);
FORCEPROP 1 LAST LOCATION PC576_5
J 0
(-600 4500);
DISPLAY 0.489362 (-600 4500);
PAINT SKYBLUE (-600 4500);
FORCEPROP 0 LAST $SEC 1
J 0
(-600 4525);
DISPLAY 0.680851 (-600 4525);
PAINT MONO (-600 4525);
DISPLAY INVISIBLE (-600 4525);
FORCEPROP 0 LAST CDS_SEC 1
J 0
(-600 4525);
DISPLAY 1.021277 (-600 4525);
DISPLAY INVISIBLE (-600 4525);
FORCEPROP 1 LASTPIN (-650 4500) $PN 1
J 0
(-640 4480);
DISPLAY 0.489362 (-640 4480);
PAINT MONO (-640 4480);
FORCEPROP 1 LASTPIN (-650 4300) $PN 2
J 0
(-640 4280);
DISPLAY 0.489362 (-640 4280);
PAINT MONO (-640 4280);
FORCEPROP 1 LAST PACK_TYPE C0805
J 0
(-600 4200);
DISPLAY 0.489362 (-600 4200);
PAINT SKYBLUE (-600 4200);
FORCEPROP 1 LAST MATERIAL X6S
J 0
(-600 4300);
DISPLAY 0.489362 (-600 4300);
PAINT SKYBLUE (-600 4300);
FORCEPROP 1 LAST TOLERANCE 20%
J 0
(-600 4350);
DISPLAY 0.489362 (-600 4350);
PAINT SKYBLUE (-600 4350);
FORCEPROP 1 LAST VALUE 22UF
J 0
(-600 4450);
DISPLAY 0.489362 (-600 4450);
PAINT SKYBLUE (-600 4450);
FORCEPROP 1 LAST VOLTAGE 4V
J 0
(-600 4400);
DISPLAY 0.489362 (-600 4400);
PAINT SKYBLUE (-600 4400);
FORCEPROP 2 LAST CDS_LIB pure_quanta
J 0
(-650 4400);
DISPLAY INVISIBLE (-650 4400);
FORCEPROP 1 LAST PATH I71
J 0
(-600 4550);
DISPLAY 0.978723 (-600 4550);
PAINT WHITE (-600 4550);
DISPLAY INVISIBLE (-600 4550);
FORCEPROP 1 LAST PART_NUMBER CH622KMEA03
J 0
(-600 4250);
DISPLAY 0.489362 (-600 4250);
PAINT SKYBLUE (-600 4250);
DISPLAY INVISIBLE (-600 4250);
FORCEADD VCC_CORE..1
(-650 4725);
FORCEPROP 3 LASTPIN (-650 4675) SIG_NAME PVDDCR_CPU0_P0\g
J 0
(-640 4685);
DISPLAY 0.659574 (-640 4685);
PAINT MONO (-640 4685);
DISPLAY INVISIBLE (-640 4685);
FORCEPROP 1 LAST HDL_POWER PVDDCR_CPU0_P0
J 1
(-650 4775);
DISPLAY 0.489362 (-650 4775);
PAINT GREEN (-650 4775);
FORCEPROP 2 LAST CDS_LIB pure_quanta_power
J 0
(-650 4725);
DISPLAY INVISIBLE (-650 4725);
FORCEPROP 1 LAST PATH I72
J 0
(-600 4750);
DISPLAY 0.872340 (-600 4750);
PAINT AQUA (-600 4750);
DISPLAY INVISIBLE (-600 4750);
FORCEADD ISL99390FRZTR5935..1
(-5700 1850);
FORCEPROP 1 LAST LOCATION PU10
J 0
(-6000 2725);
DISPLAY 0.489362 (-6000 2725);
PAINT SKYBLUE (-6000 2725);
FORCEPROP 0 LAST $SEC 1
J 0
(-6000 2875);
DISPLAY 0.680851 (-6000 2875);
PAINT MONO (-6000 2875);
DISPLAY INVISIBLE (-6000 2875);
FORCEPROP 0 LAST CDS_SEC 1
J 0
(-6000 2875);
DISPLAY 1.021277 (-6000 2875);
DISPLAY INVISIBLE (-6000 2875);
FORCEPROP 0 LASTPIN (-5300 1400) $PN 2
J 0
(-5290 1410);
DISPLAY 0.489362 (-5290 1410);
PAINT MONO (-5290 1410);
FORCEPROP 0 LASTPIN (-5300 2200) $PN 33
J 0
(-5290 2210);
DISPLAY 0.489362 (-5290 2210);
PAINT MONO (-5290 2210);
FORCEPROP 0 LASTPIN (-6150 1600) $PN 31
J 2
(-6160 1610);
DISPLAY 0.489362 (-6160 1610);
PAINT MONO (-6160 1610);
FORCEPROP 0 LASTPIN (-6150 2000) $PN 35
J 2
(-6160 2010);
DISPLAY 0.489362 (-6160 2010);
PAINT MONO (-6160 2010);
FORCEPROP 0 LASTPIN (-5300 1550) $PN 6
J 0
(-5290 1560);
DISPLAY 0.489362 (-5290 1560);
PAINT MONO (-5290 1560);
FORCEPROP 0 LASTPIN (-5300 1500) $PN 41
J 0
(-5290 1510);
DISPLAY 0.489362 (-5290 1510);
PAINT MONO (-5290 1510);
FORCEPROP 0 LASTPIN (-6150 1850) $PN 38
J 2
(-6160 1860);
DISPLAY 0.489362 (-6160 1860);
PAINT MONO (-6160 1860);
FORCEPROP 0 LASTPIN (-6150 1550) $PN 37
J 2
(-6160 1560);
DISPLAY 0.489362 (-6160 1560);
PAINT MONO (-6160 1560);
FORCEPROP 0 LASTPIN (-5300 1350) $PN 5
J 0
(-5290 1360);
DISPLAY 0.489362 (-5290 1360);
PAINT MONO (-5290 1360);
FORCEPROP 0 LASTPIN (-5300 1300) $PN 7_9-20_24
J 0
(-5290 1310);
DISPLAY 0.489362 (-5290 1310);
PAINT MONO (-5290 1310);
FORCEPROP 0 LASTPIN (-5300 1250) $PN 40
J 0
(-5290 1260);
DISPLAY 0.489362 (-5290 1260);
PAINT MONO (-5290 1260);
FORCEPROP 0 LASTPIN (-5300 1950) $PN 32
J 0
(-5290 1960);
DISPLAY 0.489362 (-5290 1960);
PAINT MONO (-5290 1960);
FORCEPROP 0 LASTPIN (-6150 2500) $PN 4
J 2
(-6160 2510);
DISPLAY 0.489362 (-6160 2510);
PAINT MONO (-6160 2510);
FORCEPROP 0 LASTPIN (-6150 1250) $PN 34
J 2
(-6160 1260);
DISPLAY 0.489362 (-6160 1260);
PAINT MONO (-6160 1260);
FORCEPROP 0 LASTPIN (-6150 1750) $PN 39
J 2
(-6160 1760);
DISPLAY 0.489362 (-6160 1760);
PAINT MONO (-6160 1760);
FORCEPROP 0 LASTPIN (-5300 1850) $PN 10_19
J 0
(-5290 1860);
DISPLAY 0.489362 (-5290 1860);
PAINT MONO (-5290 1860);
FORCEPROP 0 LASTPIN (-6150 1350) $PN 36
J 2
(-6160 1360);
DISPLAY 0.489362 (-6160 1360);
PAINT MONO (-6160 1360);
FORCEPROP 0 LASTPIN (-6150 2200) $PN 3
J 2
(-6160 2210);
DISPLAY 0.489362 (-6160 2210);
PAINT MONO (-6160 2210);
FORCEPROP 0 LASTPIN (-5300 2500) $PN 25_29
J 0
(-5290 2510);
DISPLAY 0.489362 (-5290 2510);
PAINT MONO (-5290 2510);
FORCEPROP 0 LASTPIN (-5300 2450) $PN 30
J 0
(-5290 2460);
DISPLAY 0.489362 (-5290 2460);
PAINT MONO (-5290 2460);
FORCEPROP 0 LASTPIN (-5300 1600) $PN 1
J 0
(-5290 1610);
DISPLAY 0.489362 (-5290 1610);
PAINT MONO (-5290 1610);
FORCEPROP 2 LAST VALUE ISL99390FRZ-TR5935
J 0
(-6000 2775);
DISPLAY 0.489362 (-6000 2775);
PAINT SKYBLUE (-6000 2775);
FORCEPROP 1 LAST MATERIAL IC
J 0
(-6000 2575);
DISPLAY 0.489362 (-6000 2575);
PAINT SKYBLUE (-6000 2575);
FORCEPROP 2 LAST PART_TYPE SMLF
J 0
(-6000 2825);
DISPLAY 1.021277 (-6000 2825);
FORCEPROP 1 LAST CDS_LMAN_SYM_OUTLINE -300,700,250,-650
J 0
(-5700 1850);
DISPLAY 0.468085 (-5700 1850);
PAINT GREEN (-5700 1850);
DISPLAY INVISIBLE (-5700 1850);
FORCEPROP 1 LAST NEEDS_NO_SIZE TRUE
J 0
(-5700 1850);
DISPLAY 0.723404 (-5700 1850);
PAINT GREEN (-5700 1850);
DISPLAY INVISIBLE (-5700 1850);
FORCEPROP 2 LAST CDS_LIB pure_quanta
J 0
(-5700 1850);
DISPLAY INVISIBLE (-5700 1850);
FORCEPROP 1 LAST PATH I73
J 0
(-5700 1850);
DISPLAY 0.723404 (-5700 1850);
PAINT GREEN (-5700 1850);
DISPLAY INVISIBLE (-5700 1850);
FORCEPROP 1 LAST PART_NUMBER AL099390004
J 0
(-6000 2650);
DISPLAY 0.489362 (-6000 2650);
PAINT SKYBLUE (-6000 2650);
DISPLAY INVISIBLE (-6000 2650);
FORCEADD Q_RES..1
(-6875 1550);
FORCEPROP 1 LAST LOCATION PR431
J 0
(-6900 1600);
DISPLAY 0.489362 (-6900 1600);
PAINT SKYBLUE (-6900 1600);
FORCEPROP 0 LAST $SEC 1
J 0
(-6875 1625);
DISPLAY 0.680851 (-6875 1625);
PAINT MONO (-6875 1625);
DISPLAY INVISIBLE (-6875 1625);
FORCEPROP 0 LAST CDS_SEC 1
J 0
(-6875 1625);
DISPLAY 1.021277 (-6875 1625);
DISPLAY INVISIBLE (-6875 1625);
FORCEPROP 1 LASTPIN (-6975 1550) $PN 1
J 0
(-6963 1562);
DISPLAY 0.489362 (-6963 1562);
PAINT MONO (-6963 1562);
FORCEPROP 1 LASTPIN (-6775 1550) $PN 2
J 0
(-6813 1562);
DISPLAY 0.489362 (-6813 1562);
PAINT MONO (-6813 1562);
FORCEPROP 1 LAST PACK_TYPE 0402LF
J 0
(-6775 1500);
DISPLAY 0.489362 (-6775 1500);
PAINT SKYBLUE (-6775 1500);
FORCEPROP 1 LAST VALUE 8.87K
J 2
(-7000 1575);
DISPLAY 0.489362 (-7000 1575);
PAINT SKYBLUE (-7000 1575);
FORCEPROP 1 LAST TOLERANCE 1%
J 0
(-6750 1575);
DISPLAY 0.489362 (-6750 1575);
PAINT SKYBLUE (-6750 1575);
FORCEPROP 1 LAST MATERIAL EMPTY
J 0
(-7175 1450);
DISPLAY 0.489362 (-7175 1450);
PAINT RED (-7175 1450);
FORCEPROP 1 LAST WATTAGE 1/16W
J 0
(-6775 1450);
DISPLAY 0.489362 (-6775 1450);
PAINT SKYBLUE (-6775 1450);
FORCEPROP 2 LAST CDS_LIB pure_quanta
J 0
(-6875 1550);
DISPLAY INVISIBLE (-6875 1550);
FORCEPROP 1 LAST PATH I8
J 0
(-6925 1700);
DISPLAY 0.978723 (-6925 1700);
PAINT WHITE (-6925 1700);
DISPLAY INVISIBLE (-6925 1700);
FORCEPROP 1 LAST PART_NUMBER CS28872FB01
J 0
(-7175 1500);
DISPLAY 0.489362 (-7175 1500);
PAINT SKYBLUE (-7175 1500);
DISPLAY INVISIBLE (-7175 1500);
FORCEADD OFFPAGE..2
R 2
(-6850 1850);
FORCEPROP 2 LAST $XR0 193 
J 0
(-7135 1850);
DISPLAY 0.638298 (-7135 1850);
PAINT MONO (-7135 1850);
FORCEPROP 2 LAST CDS_LIB standard
J 2
(-6850 1850);
DISPLAY INVISIBLE (-6850 1850);
FORCEPROP 1 LAST OFFPAGE TRUE
J 2
(-7175 1725);
DISPLAY 0.872340 (-7175 1725);
PAINT GREEN (-7175 1725);
DISPLAY INVISIBLE (-7175 1725);
FORCEPROP 1 LAST COMMENT_BODY TRUE
J 2
(-6805 1755);
DISPLAY 0.872340 (-6805 1755);
PAINT GREEN (-6805 1755);
DISPLAY INVISIBLE (-6805 1755);
FORCEPROP 2 LAST PATH I9
J 0
(-7100 1900);
DISPLAY 0.680851 (-7100 1900);
DISPLAY INVISIBLE (-7100 1900);
FORCEADD DNS..1
(-4225 4400);
PAINT RED (-4225 4400);
FORCEPROP 2 LAST CDS_LIB mstr_misc
J 0
(-4225 4400);
DISPLAY INVISIBLE (-4225 4400);
FORCEPROP 1 LAST COMMENT_BODY TRUE
R 1
J 0
(-4150 4175);
DISPLAY 0.872340 (-4150 4175);
PAINT GREEN (-4150 4175);
DISPLAY INVISIBLE (-4150 4175);
FORCEADD DNS..1
(-6875 4250);
PAINT RED (-6875 4250);
FORCEPROP 2 LAST CDS_LIB mstr_misc
J 0
(-6875 4250);
DISPLAY INVISIBLE (-6875 4250);
FORCEPROP 1 LAST COMMENT_BODY TRUE
R 1
J 0
(-6800 4025);
DISPLAY 0.872340 (-6800 4025);
PAINT GREEN (-6800 4025);
DISPLAY INVISIBLE (-6800 4025);
FORCEADD DNS..1
(-4225 3950);
PAINT RED (-4225 3950);
FORCEPROP 2 LAST CDS_LIB mstr_misc
J 0
(-4225 3950);
DISPLAY INVISIBLE (-4225 3950);
FORCEPROP 1 LAST COMMENT_BODY TRUE
R 1
J 0
(-4150 3725);
DISPLAY 0.872340 (-4150 3725);
PAINT GREEN (-4150 3725);
DISPLAY INVISIBLE (-4150 3725);
FORCEADD DNS..1
(-4250 1675);
PAINT RED (-4250 1675);
FORCEPROP 2 LAST CDS_LIB mstr_misc
J 0
(-4250 1675);
DISPLAY INVISIBLE (-4250 1675);
FORCEPROP 1 LAST COMMENT_BODY TRUE
R 1
J 0
(-4175 1450);
DISPLAY 0.872340 (-4175 1450);
PAINT GREEN (-4175 1450);
DISPLAY INVISIBLE (-4175 1450);
FORCEADD DNS..1
(-4250 1175);
PAINT RED (-4250 1175);
FORCEPROP 2 LAST CDS_LIB mstr_misc
J 0
(-4250 1175);
DISPLAY INVISIBLE (-4250 1175);
FORCEPROP 1 LAST COMMENT_BODY TRUE
R 1
J 0
(-4175 950);
DISPLAY 0.872340 (-4175 950);
PAINT GREEN (-4175 950);
DISPLAY INVISIBLE (-4175 950);
FORCEADD DNS..1
(-6875 1525);
PAINT RED (-6875 1525);
FORCEPROP 2 LAST CDS_LIB mstr_misc
J 0
(-6875 1525);
DISPLAY INVISIBLE (-6875 1525);
FORCEPROP 1 LAST COMMENT_BODY TRUE
R 1
J 0
(-6800 1300);
DISPLAY 0.872340 (-6800 1300);
PAINT GREEN (-6800 1300);
DISPLAY INVISIBLE (-6800 1300);
FORCEADD QUANTA_TITLE_BLOCK_C..1
(0 0);
FORCEPROP 0 LAST CDS_CON_LAST_MODIFIED Thu Sep 14 16:12:40 2023
J 0
(-1885 15);
DISPLAY INVISIBLE (-1885 15);
FORCEPROP 1 LAST CUSTOM_TXT_CDS <CON_LAST_MODIFIED>
J 0
(-1885 15);
DISPLAY 0.978723 (-1885 15);
FORCEPROP 2 LAST CUSTOM_TXT_CDS <XR_PAGE_TITLE>
J 0
(-7890 5250);
DISPLAY 0.638298 (-7890 5250);
PAINT PINK (-7890 5250);
DISPLAY INVISIBLE (-7890 5250);
FORCEPROP 1 LAST CUSTOM_TXT_CDS <NAME_2>
J 0
(-3175 50);
FORCEPROP 1 LAST CUSTOM_TXT_CDS <NAME_1>
J 0
(-3175 175);
FORCEPROP 1 LAST CUSTOM_TXT_CDS <Q_NUMBER>
J 0
(-1403 103);
DISPLAY 1.212766 (-1403 103);
FORCEPROP 1 LAST CUSTOM_TXT_CDS <Q_PROJ>
J 0
(-2382 102);
DISPLAY 1.212766 (-2382 102);
FORCEPROP 1 LAST CUSTOM_TXT_CDS <Q_REV>
J 0
(-184 103);
DISPLAY 1.212766 (-184 103);
FORCEPROP 1 LAST CUSTOM_TXT_CDS <CON_PAGE_NUM> OF <CON_TOTAL_PAGES>
J 0
(-446 18);
DISPLAY 0.978723 (-446 18);
FORCEPROP 1 LAST Q_TITLE PVDDCR_CPU0_P0 VR PHASE 5&6
J 0
(-9325 50);
DISPLAY 2.446809 (-9325 50);
PAINT GREEN (-9325 50);
FORCEPROP 2 LAST CDS_LIB pure_quanta
J 0
(0 0);
DISPLAY INVISIBLE (0 0);
FORCEPROP 1 LAST CDS_LMAN_SYM_OUTLINE -9475,6775,100,-125
J 0
(0 0);
DISPLAY 0.468085 (0 0);
PAINT GREEN (0 0);
DISPLAY INVISIBLE (0 0);
FORCEPROP 2 LAST PAGE_BORDER TRUE
J 0
(-7890 5250);
DISPLAY 0.638298 (-7890 5250);
PAINT PINK (-7890 5250);
DISPLAY INVISIBLE (-7890 5250);
FORCEPROP 2 LAST CDS_XR_PAGE_TITLE CR-196 : @T6G_MB_LIB.T6G(SCH_1):PAGE196
J 0
(-7890 5250);
DISPLAY 0.638298 (-7890 5250);
PAINT PINK (-7890 5250);
DISPLAY INVISIBLE (-7890 5250);
FORCEPROP 1 LAST Q_DEPT BU9
J 1
(-3763 49);
DISPLAY 1.957447 (-3763 49);
PAINT GREEN (-3763 49);
DISPLAY INVISIBLE (-3763 49);
FORCEPROP 1 LAST COMMENT_BODY TRUE
J 0
(12 -13);
DISPLAY 0.978723 (12 -13);
PAINT GREEN (12 -13);
DISPLAY INVISIBLE (12 -13);
WIRE 16 -1 (-7200 2100)(-7200 2050);
WIRE 16 -1 (-6850 2625)(-6850 2500);
WIRE 16 -1 (-7525 4200)(-7525 4075);
WIRE 16 -1 (-4225 1075)(-4225 1000);
WIRE 16 -1 (-7525 1475)(-7525 1350);
WIRE 16 -1 (-4200 3850)(-4200 3775);
WIRE 16 -1 (-6975 4275)(-7200 4275);
WIRE 16 -1 (-7200 4275)(-7200 4150);
WIRE 16 -1 (-7200 4825)(-7200 4775);
WIRE 16 -1 (-6850 5325)(-6850 5225);
WIRE 16 -1 (-6975 1550)(-7200 1550);
WIRE 16 -1 (-7200 1550)(-7200 1425);
WIRE 16 -1 (-3925 2625)(-3925 2500);
WIRE 16 -1 (-3625 2500)(-3925 2500);
WIRE 16 -1 (-4250 2500)(-3925 2500);
WIRE 16 -1 (-4250 2625)(-4250 2500);
WIRE 16 -1 (-4575 2500)(-4250 2500);
WIRE 16 -1 (-3625 2625)(-3625 2500);
WIRE 16 -1 (-3625 2500)(-3625 2425);
WIRE 16 -1 (-4575 2625)(-4575 2500);
WIRE 16 -1 (-4950 2500)(-4575 2500);
WIRE 16 -1 (-4950 2625)(-4950 2500);
WIRE 16 -1 (-5200 2900)(-5200 2500);
WIRE 16 -1 (-5200 2900)(-4950 2900);
WIRE 16 -1 (-5300 2500)(-5200 2500);
WIRE 16 -1 (-5200 2500)(-5200 2450);
WIRE 16 -1 (-5200 2450)(-5300 2450);
WIRE 16 -1 (-4950 2900)(-4575 2900);
WIRE 16 -1 (-4950 2825)(-4950 2900);
WIRE 16 -1 (-4575 2900)(-4250 2900);
WIRE 16 -1 (-4575 2825)(-4575 2900);
WIRE 16 -1 (-4250 2900)(-3925 2900);
WIRE 16 -1 (-4250 2825)(-4250 2900);
WIRE 16 -1 (-3925 2900)(-3625 2900);
WIRE 16 -1 (-3925 2900)(-3925 2825);
WIRE 16 -1 (-3625 2975)(-3625 2900);
WIRE 16 -1 (-3625 2900)(-3625 2825);
WIRE 16 -1 (-4200 4575)(-2875 4575);
WIRE 16 -1 (-4200 4575)(-4200 4500);
WIRE 16 -1 (-5300 4575)(-4200 4575);
FORCEPROP 2 LAST SIG_NAME SW_PVDDCR_CPU0_P0_SW5
J 0
(-5185 4585);
DISPLAY 0.489362 (-5185 4585);
FORCEPROP 2 LASTPROP $XRERR UNIQUE?
J 0
(-5425 4585);
DISPLAY 0.638298 (-5425 4585);
PAINT MONO (-5425 4585);
DISPLAY INVISIBLE (-5425 4585);
WIRE 16 -1 (-3275 4700)(-3275 4675);
WIRE 16 -1 (-3275 4675)(-5300 4675);
FORCEPROP 2 LAST SIG_NAME SW_PVDDCR_CPU0_P0_PH5
J 0
(-5185 4685);
DISPLAY 0.489362 (-5185 4685);
FORCEPROP 2 LASTPROP $XRERR UNIQUE?
J 0
(-5425 4685);
DISPLAY 0.638298 (-5425 4685);
PAINT MONO (-5425 4685);
DISPLAY INVISIBLE (-5425 4685);
WIRE 16 -1 (-5300 4925)(-4375 4925);
FORCEPROP 2 LAST SIG_NAME SW_PVDDCR_CPU0_P0_BOOT5
J 0
(-5185 4935);
DISPLAY 0.489362 (-5185 4935);
FORCEPROP 2 LASTPROP $XRERR UNIQUE?
J 0
(-5425 4935);
DISPLAY 0.638298 (-5425 4935);
PAINT MONO (-5425 4935);
DISPLAY INVISIBLE (-5425 4935);
WIRE 16 -1 (-3900 5350)(-3900 5225);
WIRE 16 -1 (-3900 5225)(-3550 5225);
WIRE 16 -1 (-4250 5225)(-3900 5225);
WIRE 16 -1 (-4250 5350)(-4250 5225);
WIRE 16 -1 (-4575 5225)(-4250 5225);
WIRE 16 -1 (-3550 5350)(-3550 5225);
WIRE 16 -1 (-3550 5225)(-3550 5150);
WIRE 16 -1 (-4575 5350)(-4575 5225);
WIRE 16 -1 (-4950 5225)(-4575 5225);
WIRE 16 -1 (-4950 5350)(-4950 5225);
WIRE 16 -1 (-3550 5700)(-3550 5625);
WIRE 16 -1 (-3550 5625)(-3550 5550);
WIRE 16 -1 (-3900 5625)(-3550 5625);
WIRE 16 -1 (-3900 5625)(-3900 5550);
WIRE 16 -1 (-4250 5625)(-3900 5625);
WIRE 16 -1 (-4250 5550)(-4250 5625);
WIRE 16 -1 (-4575 5625)(-4250 5625);
WIRE 16 -1 (-4575 5550)(-4575 5625);
WIRE 16 -1 (-4950 5625)(-4575 5625);
WIRE 16 -1 (-4950 5550)(-4950 5625);
WIRE 16 -1 (-5200 5625)(-4950 5625);
WIRE 16 -1 (-5200 5625)(-5200 5225);
WIRE 16 -1 (-5300 5225)(-5200 5225);
WIRE 16 -1 (-5200 5225)(-5200 5175);
WIRE 16 -1 (-5200 5175)(-5300 5175);
WIRE 16 -1 (-7700 4475)(-7525 4475);
WIRE 16 -1 (-6150 4475)(-7525 4475);
FORCEPROP 2 LAST SIG_NAME PVDDCR_CPU0_P0_VCCS
J 2
(-6210 4485);
DISPLAY 0.489362 (-6210 4485);
WIRE 16 -1 (-7525 4400)(-7525 4475);
WIRE 16 -1 (-3275 4925)(-3275 4900);
WIRE 16 -1 (-4175 4925)(-3275 4925);
FORCEPROP 2 LAST SIG_NAME SW_PVDDCR_CPU0_P0_BOOT5_RC
J 2
(-3310 4935);
DISPLAY 0.489362 (-3310 4935);
FORCEPROP 2 LASTPROP $XRERR UNIQUE?
J 0
(-3550 4935);
DISPLAY 0.638298 (-3550 4935);
PAINT MONO (-3550 4935);
DISPLAY INVISIBLE (-3550 4935);
WIRE 16 -1 (-5300 2200)(-4375 2200);
FORCEPROP 2 LAST SIG_NAME SW_PVDDCR_CPU0_P0_BOOT6
J 0
(-5185 2210);
DISPLAY 0.489362 (-5185 2210);
FORCEPROP 2 LASTPROP $XRERR UNIQUE?
J 0
(-5425 2210);
DISPLAY 0.638298 (-5425 2210);
PAINT MONO (-5425 2210);
DISPLAY INVISIBLE (-5425 2210);
WIRE 16 -1 (-3275 2200)(-3275 2175);
WIRE 16 -1 (-4175 2200)(-3275 2200);
FORCEPROP 2 LAST SIG_NAME SW_PVDDCR_CPU0_P0_BOOT6_RC
J 2
(-3310 2210);
DISPLAY 0.489362 (-3310 2210);
FORCEPROP 2 LASTPROP $XRERR UNIQUE?
J 0
(-3550 2210);
DISPLAY 0.638298 (-3550 2210);
PAINT MONO (-3550 2210);
DISPLAY INVISIBLE (-3550 2210);
WIRE 16 -1 (-3275 1975)(-3275 1950);
WIRE 16 -1 (-3275 1950)(-5300 1950);
FORCEPROP 2 LAST SIG_NAME SW_PVDDCR_CPU0_P0_PH6
J 0
(-5185 1960);
DISPLAY 0.489362 (-5185 1960);
FORCEPROP 2 LASTPROP $XRERR UNIQUE?
J 0
(-5425 1960);
DISPLAY 0.638298 (-5425 1960);
PAINT MONO (-5425 1960);
DISPLAY INVISIBLE (-5425 1960);
WIRE 16 -1 (-3350 1600)(-2875 1600);
FORCEPROP 2 LAST SIG_NAME IND_CPU0_P0_CPL0
J 0
(-3285 1625);
DISPLAY 0.489362 (-3285 1625);
FORCEPROP 2 LASTPROP $XRERR UNIQUE?
J 0
(-3525 1625);
DISPLAY 0.638298 (-3525 1625);
PAINT MONO (-3525 1625);
DISPLAY INVISIBLE (-3525 1625);
WIRE 16 -1 (-4225 1850)(-2875 1850);
WIRE 16 -1 (-4225 1850)(-4225 1775);
WIRE 16 -1 (-5300 1850)(-4225 1850);
FORCEPROP 2 LAST SIG_NAME SW_PVDDCR_CPU0_P0_SW6
J 0
(-5185 1860);
DISPLAY 0.489362 (-5185 1860);
FORCEPROP 2 LASTPROP $XRERR UNIQUE?
J 0
(-5425 1860);
DISPLAY 0.638298 (-5425 1860);
PAINT MONO (-5425 1860);
DISPLAY INVISIBLE (-5425 1860);
WIRE 16 -1 (-4225 1575)(-4225 1275);
FORCEPROP 2 LAST SIG_NAME SW_PVDDCR_CPU0_P0_SW6_RC
J 0
(-4185 1385);
DISPLAY 0.489362 (-4185 1385);
FORCEPROP 2 LASTPROP $XRERR UNIQUE?
J 0
(-4425 1385);
DISPLAY 0.638298 (-4425 1385);
PAINT MONO (-4425 1385);
DISPLAY INVISIBLE (-4425 1385);
WIRE 16 -1 (-3625 1600)(-3550 1600);
WIRE 16 -1 (-3625 1550)(-3625 1600);
WIRE 16 -1 (-1300 4575)(-1075 4575);
WIRE 16 -1 (-2075 4575)(-1300 4575);
WIRE 16 -1 (-1300 4575)(-1300 3625);
WIRE 16 -1 (-1075 4575)(-650 4575);
WIRE 16 -1 (-1075 4575)(-1075 4500);
WIRE 16 -1 (-650 4675)(-650 4575);
WIRE 16 -1 (-650 4575)(-650 4500);
WIRE 16 -1 (-1300 3625)(-3525 3625);
WIRE 16 -1 (-650 4300)(-650 4175);
WIRE 16 -1 (-650 4100)(-650 4175);
WIRE 16 -1 (-650 4175)(-1075 4175);
WIRE 16 -1 (-1075 4300)(-1075 4175);
WIRE 16 -1 (-1300 1850)(-1075 1850);
WIRE 16 -1 (-1300 1850)(-1300 800);
WIRE 16 -1 (-2075 1850)(-1300 1850);
WIRE 16 -1 (-1075 1850)(-650 1850);
WIRE 16 -1 (-1075 1850)(-1075 1775);
WIRE 16 -1 (-650 1950)(-650 1850);
WIRE 16 -1 (-650 1850)(-650 1775);
WIRE 16 -1 (-1300 800)(-3800 800);
WIRE 16 -1 (-650 1575)(-650 1450);
WIRE 16 -1 (-650 1375)(-650 1450);
WIRE 16 -1 (-650 1450)(-1075 1450);
WIRE 16 -1 (-1075 1575)(-1075 1450);
WIRE 16 -1 (-7200 5525)(-7200 5650);
WIRE 16 -1 (-6850 5650)(-7200 5650);
WIRE 16 -1 (-7200 5775)(-7200 5650);
WIRE 16 -1 (-6450 5650)(-6850 5650);
WIRE 16 -1 (-6850 5525)(-6850 5650);
WIRE 16 -1 (-6450 5225)(-6450 5650);
WIRE 16 -1 (-6450 5225)(-6150 5225);
WIRE 16 -1 (-5300 3975)(-5150 3975);
WIRE 16 -1 (-5150 3975)(-5150 4025);
WIRE 16 -1 (-5150 3900)(-5150 3975);
WIRE 16 -1 (-5150 4025)(-5150 4075);
WIRE 16 -1 (-5300 4025)(-5150 4025);
WIRE 16 -1 (-5150 4125)(-5150 4075);
WIRE 16 -1 (-5300 4075)(-5150 4075);
WIRE 16 -1 (-5150 4125)(-5300 4125);
WIRE 16 -1 (-5300 1250)(-5150 1250);
WIRE 16 -1 (-5150 1250)(-5150 1300);
WIRE 16 -1 (-5150 1175)(-5150 1250);
WIRE 16 -1 (-5150 1300)(-5150 1350);
WIRE 16 -1 (-5300 1300)(-5150 1300);
WIRE 16 -1 (-5150 1400)(-5150 1350);
WIRE 16 -1 (-5300 1350)(-5150 1350);
WIRE 16 -1 (-5150 1400)(-5300 1400);
WIRE 16 -1 (-7200 2800)(-7200 2925);
WIRE 16 -1 (-6850 2925)(-7200 2925);
WIRE 16 -1 (-7200 3075)(-7200 2925);
WIRE 16 -1 (-6475 2925)(-6850 2925);
WIRE 16 -1 (-6850 2825)(-6850 2925);
WIRE 16 -1 (-6475 2500)(-6475 2925);
WIRE 16 -1 (-6475 2500)(-6150 2500);
WIRE 16 -1 (-4000 800)(-4550 800);
FORCEPROP 2 LAST SIG_NAME PVDDCR_CPU0_P0_VOS6
J 0
(-5185 1625);
DISPLAY 0.489362 (-5185 1625);
FORCEPROP 2 LASTPROP $XRERR UNIQUE?
J 0
(-5425 1625);
DISPLAY 0.638298 (-5425 1625);
PAINT MONO (-5425 1625);
DISPLAY INVISIBLE (-5425 1625);
WIRE 16 -1 (-4550 800)(-4550 1600);
WIRE 16 -1 (-5300 1600)(-4550 1600);
WIRE 16 -1 (-3725 3625)(-4550 3625);
FORCEPROP 2 LAST SIG_NAME PVDDCR_CPU0_P0_VOS5
J 0
(-5185 4350);
DISPLAY 0.489362 (-5185 4350);
FORCEPROP 2 LASTPROP $XRERR UNIQUE?
J 0
(-5425 4350);
DISPLAY 0.638298 (-5425 4350);
PAINT MONO (-5425 4350);
DISPLAY INVISIBLE (-5425 4350);
WIRE 16 -1 (-4550 3625)(-4550 4325);
WIRE 16 -1 (-5300 4325)(-4550 4325);
WIRE 16 -1 (-7525 1675)(-7525 1750);
WIRE 16 -1 (-6150 1750)(-7525 1750);
FORCEPROP 2 LAST SIG_NAME PVDDCR_CPU0_P0_VCCS
J 2
(-6210 1760);
DISPLAY 0.489362 (-6210 1760);
WIRE 16 -1 (-7700 1750)(-7525 1750);
WIRE 16 -1 (-6150 1850)(-6800 1850);
FORCEPROP 2 LAST SIG_NAME PVDDCR_CPU0_P0_IMON6
J 2
(-6210 1860);
DISPLAY 0.489362 (-6210 1860);
WIRE 16 -1 (-6775 1550)(-6150 1550);
FORCEPROP 2 LAST SIG_NAME PVDDCR_CPU0_P0_LSET6
J 2
(-6210 1560);
DISPLAY 0.489362 (-6210 1560);
FORCEPROP 2 LASTPROP $XRERR UNIQUE?
J 0
(-6450 1560);
DISPLAY 0.638298 (-6450 1560);
PAINT MONO (-6450 1560);
DISPLAY INVISIBLE (-6450 1560);
WIRE 16 -1 (-5300 1500)(-4775 1500);
FORCEPROP 2 LAST SIG_NAME NC_PVDDCR_CPU0_P0_GL2_6
J 0
(-5185 1510);
DISPLAY 0.489362 (-5185 1510);
FORCEPROP 2 LASTPROP $XRERR UNIQUE?
J 0
(-4745 1500);
DISPLAY 0.638298 (-4745 1500);
PAINT MONO (-4745 1500);
DISPLAY INVISIBLE (-4745 1500);
WIRE 16 -1 (-5300 1550)(-4775 1550);
FORCEPROP 2 LAST SIG_NAME NC_PVDDCR_CPU0_P0_GL1_6
J 0
(-5185 1560);
DISPLAY 0.489362 (-5185 1560);
FORCEPROP 2 LASTPROP $XRERR UNIQUE?
J 0
(-4745 1550);
DISPLAY 0.638298 (-4745 1550);
PAINT MONO (-4745 1550);
DISPLAY INVISIBLE (-4745 1550);
WIRE 16 -1 (-6775 4275)(-6150 4275);
FORCEPROP 2 LAST SIG_NAME PVDDCR_CPU0_P0_LSET5
J 2
(-6210 4285);
DISPLAY 0.489362 (-6210 4285);
FORCEPROP 2 LASTPROP $XRERR UNIQUE?
J 0
(-6450 4285);
DISPLAY 0.638298 (-6450 4285);
PAINT MONO (-6450 4285);
DISPLAY INVISIBLE (-6450 4285);
WIRE 16 -1 (-6150 4325)(-6600 4325);
FORCEPROP 2 LAST SIG_NAME NC_PVDDCR_CPU0_P0_DNC5
J 2
(-6210 4335);
DISPLAY 0.489362 (-6210 4335);
FORCEPROP 2 LASTPROP $XRERR UNIQUE?
J 0
(-6840 4325);
DISPLAY 0.638298 (-6840 4325);
PAINT MONO (-6840 4325);
DISPLAY INVISIBLE (-6840 4325);
WIRE 16 -1 (-5300 4275)(-4775 4275);
FORCEPROP 2 LAST SIG_NAME NC_PVDDCR_CPU0_P0_GL1_5
J 0
(-5185 4285);
DISPLAY 0.489362 (-5185 4285);
FORCEPROP 2 LASTPROP $XRERR UNIQUE?
J 0
(-4745 4275);
DISPLAY 0.638298 (-4745 4275);
PAINT MONO (-4745 4275);
DISPLAY INVISIBLE (-4745 4275);
WIRE 16 -1 (-2075 1600)(-1600 1600);
FORCEPROP 2 LAST SIG_NAME IND_CPU0_P0_CPL6
J 0
(-1985 1610);
DISPLAY 0.489362 (-1985 1610);
WIRE 16 -1 (-3325 4325)(-2875 4325);
FORCEPROP 2 LAST SIG_NAME IND_CPU0_P0_CPL6
J 0
(-3310 4335);
DISPLAY 0.489362 (-3310 4335);
WIRE 16 -1 (-2075 4325)(-1625 4325);
FORCEPROP 2 LAST SIG_NAME IND_CPU0_P0_CPL5
J 0
(-1985 4335);
DISPLAY 0.489362 (-1985 4335);
WIRE 16 -1 (-6750 5100)(-6750 4925);
FORCEPROP 2 LAST SIG_NAME PVDDCR_CPU0_P0_VCC5
J 2
(-6260 4935);
DISPLAY 0.489362 (-6260 4935);
FORCEPROP 2 LASTPROP $XRERR UNIQUE?
J 0
(-6500 4935);
DISPLAY 0.638298 (-6500 4935);
PAINT MONO (-6500 4935);
DISPLAY INVISIBLE (-6500 4935);
WIRE 16 -1 (-6750 5100)(-7200 5100);
WIRE 16 -1 (-6750 4925)(-6150 4925);
WIRE 16 -1 (-6750 4925)(-6750 4725);
WIRE 16 -1 (-6750 4725)(-6150 4725);
WIRE 16 -1 (-7200 5325)(-7200 5100);
WIRE 16 -1 (-7200 5100)(-7200 5025);
WIRE 16 -1 (-6150 4575)(-6800 4575);
FORCEPROP 2 LAST SIG_NAME PVDDCR_CPU0_P0_IMON5
J 2
(-6210 4585);
DISPLAY 0.489362 (-6210 4585);
WIRE 16 -1 (-6150 1600)(-6600 1600);
FORCEPROP 2 LAST SIG_NAME NC_PVDDCR_CPU0_P0_DNC6
J 2
(-6210 1610);
DISPLAY 0.489362 (-6210 1610);
FORCEPROP 2 LASTPROP $XRERR UNIQUE?
J 0
(-6840 1600);
DISPLAY 0.638298 (-6840 1600);
PAINT MONO (-6840 1600);
DISPLAY INVISIBLE (-6840 1600);
WIRE 16 -1 (-6150 1250)(-6750 1250);
FORCEPROP 2 LAST SIG_NAME PVDDCR_CPU0_P0_PWM6
J 2
(-6210 1260);
DISPLAY 0.489362 (-6210 1260);
WIRE 16 -1 (-6150 1350)(-6775 1350);
FORCEPROP 2 LAST SIG_NAME PVDDCR_CPU0_P0_TEMP0
J 2
(-6210 1360);
DISPLAY 0.489362 (-6210 1360);
WIRE 16 -1 (-4200 4300)(-4200 4050);
FORCEPROP 2 LAST SIG_NAME SW_PVDDCR_CPU0_P0_SW5_RC
J 0
(-4160 4135);
DISPLAY 0.489362 (-4160 4135);
FORCEPROP 2 LASTPROP $XRERR UNIQUE?
J 0
(-4400 4135);
DISPLAY 0.638298 (-4400 4135);
PAINT MONO (-4400 4135);
DISPLAY INVISIBLE (-4400 4135);
WIRE 16 -1 (-6150 4075)(-6775 4075);
FORCEPROP 2 LAST SIG_NAME PVDDCR_CPU0_P0_TEMP0
J 2
(-6210 4085);
DISPLAY 0.489362 (-6210 4085);
WIRE 16 -1 (-7200 2375)(-6750 2375);
WIRE 16 -1 (-7200 2600)(-7200 2375);
WIRE 16 -1 (-7200 2375)(-7200 2300);
WIRE 16 -1 (-6750 2375)(-6750 2200);
FORCEPROP 2 LAST SIG_NAME PVDDCR_CPU0_P0_VCC6
J 2
(-6260 2210);
DISPLAY 0.489362 (-6260 2210);
FORCEPROP 2 LASTPROP $XRERR UNIQUE?
J 0
(-6500 2210);
DISPLAY 0.638298 (-6500 2210);
PAINT MONO (-6500 2210);
DISPLAY INVISIBLE (-6500 2210);
WIRE 16 -1 (-6750 2200)(-6150 2200);
WIRE 16 -1 (-6750 2200)(-6750 2000);
WIRE 16 -1 (-6750 2000)(-6150 2000);
WIRE 16 -1 (-6150 3975)(-6750 3975);
FORCEPROP 2 LAST SIG_NAME PVDDCR_CPU0_P0_PWM5
J 2
(-6210 3985);
DISPLAY 0.489362 (-6210 3985);
WIRE 16 -1 (-5300 4225)(-4775 4225);
FORCEPROP 2 LAST SIG_NAME NC_PVDDCR_CPU0_P0_GL2_5
J 0
(-5185 4235);
DISPLAY 0.489362 (-5185 4235);
FORCEPROP 2 LASTPROP $XRERR UNIQUE?
J 0
(-4745 4225);
DISPLAY 0.638298 (-4745 4225);
PAINT MONO (-4745 4225);
DISPLAY INVISIBLE (-4745 4225);
DOT 1 (-7525 4475);
DOT 1 (-7525 1750);
DOT 1 (-7200 2375);
DOT 1 (-7200 2925);
DOT 1 (-6850 2925);
DOT 1 (-6750 2200);
DOT 1 (-5150 1300);
DOT 1 (-5150 1250);
DOT 1 (-5150 1350);
DOT 1 (-4225 1850);
DOT 1 (-5200 2500);
DOT 1 (-5150 3975);
DOT 1 (-4575 2500);
DOT 1 (-4575 2900);
DOT 1 (-4250 2500);
DOT 1 (-4250 2900);
DOT 1 (-3925 2500);
DOT 1 (-3925 2900);
DOT 1 (-5150 4025);
DOT 1 (-7200 5100);
DOT 1 (-7200 5650);
DOT 1 (-6850 5650);
DOT 1 (-6750 4925);
DOT 1 (-5150 4075);
DOT 1 (-5200 5225);
DOT 1 (-4950 5625);
DOT 1 (-4200 4575);
DOT 1 (-4250 5225);
DOT 1 (-4575 5625);
DOT 1 (-4250 5625);
DOT 1 (-3900 5225);
DOT 1 (-3900 5625);
DOT 1 (-3625 2900);
DOT 1 (-1300 1850);
DOT 1 (-650 1450);
DOT 1 (-1075 1850);
DOT 1 (-3550 5225);
DOT 1 (-3550 5625);
DOT 1 (-1300 4575);
DOT 1 (-650 4175);
DOT 1 (-1075 4575);
DOT 1 (-650 4575);
DOT 1 (-650 1850);
DOT 1 (-3625 2500);
DOT 1 (-4575 5225);
DOT 1 (-4950 2900);
FORCENOTE
PVDDCR_CPU0_P0_PHASE6
(-6300 3250) 0;
DISPLAY LEFT (-6300 3250);
DISPLAY 1.595745 (-6300 3250);
PAINT WHITE (-6300 3250);
FORCENOTE
DCR=2-3,0.27M OHM
(-2025 1975) 0;
DISPLAY LEFT (-2025 1975);
DISPLAY 0.638298 (-2025 1975);
PAINT WHITE (-2025 1975);
FORCENOTE
11.0*7.5*12.5
(-2025 2075) 0;
DISPLAY LEFT (-2025 2075);
DISPLAY 0.638298 (-2025 2075);
PAINT WHITE (-2025 2075);
FORCENOTE
PGL6303.151HLT
(-2025 2175) 0;
DISPLAY LEFT (-2025 2175);
DISPLAY 0.638298 (-2025 2175);
PAINT WHITE (-2025 2175);
FORCENOTE
ISAT:70A@100C
(-2025 2125) 0;
DISPLAY LEFT (-2025 2125);
DISPLAY 0.638298 (-2025 2125);
PAINT WHITE (-2025 2125);
FORCENOTE
PGL6303.151HLT
(-2025 4875) 0;
DISPLAY LEFT (-2025 4875);
DISPLAY 0.638298 (-2025 4875);
PAINT WHITE (-2025 4875);
FORCENOTE
ISAT:70A@100C
(-2025 4825) 0;
DISPLAY LEFT (-2025 4825);
DISPLAY 0.638298 (-2025 4825);
PAINT WHITE (-2025 4825);
FORCENOTE
11.0*7.5*12.5
(-2025 4775) 0;
DISPLAY LEFT (-2025 4775);
DISPLAY 0.638298 (-2025 4775);
PAINT WHITE (-2025 4775);
FORCENOTE
DCR=2-3,0.27M OHM
(-2025 4675) 0;
DISPLAY LEFT (-2025 4675);
DISPLAY 0.638298 (-2025 4675);
PAINT WHITE (-2025 4675);
FORCENOTE
DCR=1-4,0.105M OHM
(-2025 4725) 0;
DISPLAY LEFT (-2025 4725);
DISPLAY 0.638298 (-2025 4725);
PAINT WHITE (-2025 4725);
FORCENOTE
2ND=CV+15^0TZ01
(-2025 4625) 0;
DISPLAY LEFT (-2025 4625);
DISPLAY 0.638298 (-2025 4625);
PAINT WHITE (-2025 4625);
FORCENOTE
2ND=CV+15^0TZ01
(-2025 1925) 0;
DISPLAY LEFT (-2025 1925);
DISPLAY 0.638298 (-2025 1925);
PAINT WHITE (-2025 1925);
FORCENOTE
DCR=1-4,0.105M OHM
(-2025 2025) 0;
DISPLAY LEFT (-2025 2025);
DISPLAY 0.638298 (-2025 2025);
PAINT WHITE (-2025 2025);
FORCENOTE
PVDDCR_CPU0_P0_PHASE5
(-6300 5975) 0;
DISPLAY LEFT (-6300 5975);
DISPLAY 1.595745 (-6300 5975);
PAINT WHITE (-6300 5975);
FORCENOTE
6.5*6.5*10.0
(-3500 1425) 0;
DISPLAY LEFT (-3500 1425);
DISPLAY 0.638298 (-3500 1425);
PAINT WHITE (-3500 1425);
FORCENOTE
DCR=0.17M OHM
(-3500 1375) 0;
DISPLAY LEFT (-3500 1375);
DISPLAY 0.638298 (-3500 1375);
PAINT WHITE (-3500 1375);
FORCENOTE
2ND=CV+12^0EZ04
(-3500 1325) 0;
DISPLAY LEFT (-3500 1325);
DISPLAY 0.638298 (-3500 1325);
PAINT WHITE (-3500 1325);
FORCENOTE
ISAT:60A@100C
(-3500 1475) 0;
DISPLAY LEFT (-3500 1475);
DISPLAY 0.638298 (-3500 1475);
PAINT WHITE (-3500 1475);
FORCENOTE
PGL6312.121AHLT
(-3500 1525) 0;
DISPLAY LEFT (-3500 1525);
DISPLAY 0.638298 (-3500 1525);
PAINT WHITE (-3500 1525);
QUIT
